FILE_TYPE = MACRO_DRAWING;
SET COLOR_WIRE YELLOW;
SET COLOR_PROP ORANGE;
SET COLOR_DOT WHITE;
SET COLOR_ARC YELLOW;
SET COLOR_BODY GREEN;
SET COLOR_NOTE PURPLE;
SET PROP_DISPLAY VALUE;
SET PAGE_NUMBER P299;
FORCEADD OFFPAGE..4
R 2
(-3250 -600);
FORCEPROP 2 LAST $XR0 139 
J 0
(-3532 -600);
DISPLAY 0.638298 (-3532 -600);
PAINT MONO (-3532 -600);
FORCEPROP 2 LAST PATH I1
J 0
(-3525 -550);
DISPLAY 1.021277 (-3525 -550);
DISPLAY INVISIBLE (-3525 -550);
FORCEPROP 1 LAST OFFPAGE TRUE
J 2
(-3575 -725);
DISPLAY 0.872340 (-3575 -725);
PAINT GREEN (-3575 -725);
DISPLAY INVISIBLE (-3575 -725);
FORCEPROP 1 LAST COMMENT_BODY TRUE
J 2
(-3225 -700);
DISPLAY 0.872340 (-3225 -700);
PAINT GREEN (-3225 -700);
DISPLAY INVISIBLE (-3225 -700);
FORCEPROP 2 LAST CDS_LIB standard
J 0
(-3250 -600);
DISPLAY INVISIBLE (-3250 -600);
FORCEADD UNIVERSAL_POWER..1
(-2925 1500);
FORCEPROP 3 LASTPIN (-2925 1450) SIG_NAME P3V3_AUX\g
J 0
(-2915 1460);
DISPLAY 0.659574 (-2915 1460);
PAINT MONO (-2915 1460);
DISPLAY INVISIBLE (-2915 1460);
FORCEPROP 1 LAST HDL_POWER P3V3_AUX
J 1
(-2925 1550);
DISPLAY 0.872340 (-2925 1550);
PAINT GREEN (-2925 1550);
FORCEPROP 2 LAST CDS_LIB logical_power
J 0
(-2925 1500);
PAINT MONO (-2925 1500);
DISPLAY INVISIBLE (-2925 1500);
FORCEPROP 1 LAST PATH I10
J 0
(-2875 1525);
DISPLAY 0.872340 (-2875 1525);
PAINT AQUA (-2875 1525);
DISPLAY INVISIBLE (-2875 1525);
FORCEADD UNIVERSAL_GND..1
(-2950 1950);
FORCEPROP 3 LASTPIN (-2950 2000) SIG_NAME GND\g
J 0
(-2940 2010);
DISPLAY 0.659574 (-2940 2010);
PAINT MONO (-2940 2010);
DISPLAY INVISIBLE (-2940 2010);
FORCEPROP 1 LAST PATH I11
J 0
(-2875 1950);
DISPLAY 0.872340 (-2875 1950);
PAINT AQUA (-2875 1950);
DISPLAY INVISIBLE (-2875 1950);
FORCEPROP 1 LAST HDL_POWER GND
J 1
(-2925 1875);
DISPLAY 0.872340 (-2925 1875);
PAINT GREEN (-2925 1875);
DISPLAY INVISIBLE (-2925 1875);
FORCEPROP 2 LAST CDS_LIB logical_power
J 0
(-2950 1950);
DISPLAY INVISIBLE (-2950 1950);
FORCEADD OFFPAGE..4
R 2
(-3175 2325);
FORCEPROP 2 LAST $XR0 141 
J 0
(-3427 2325);
DISPLAY 0.638298 (-3427 2325);
PAINT MONO (-3427 2325);
FORCEPROP 2 LAST CDS_LIB standard
J 0
(-3175 2325);
DISPLAY INVISIBLE (-3175 2325);
FORCEPROP 1 LAST COMMENT_BODY TRUE
J 2
(-3150 2225);
DISPLAY 0.872340 (-3150 2225);
PAINT GREEN (-3150 2225);
DISPLAY INVISIBLE (-3150 2225);
FORCEPROP 1 LAST OFFPAGE TRUE
J 2
(-3500 2200);
DISPLAY 0.872340 (-3500 2200);
PAINT GREEN (-3500 2200);
DISPLAY INVISIBLE (-3500 2200);
FORCEPROP 2 LAST PATH I12
J 0
(-3125 2400);
DISPLAY 1.021277 (-3125 2400);
DISPLAY INVISIBLE (-3125 2400);
FORCEADD Q_CAP..1
(100 1300);
FORCEPROP 1 LAST PART_NUMBER TMP_QCH21006JB10
J 0
(150 1150);
DISPLAY 0.638298 (150 1150);
DISPLAY INVISIBLE (150 1150);
FORCEPROP 1 LAST TOLERANCE 5%
J 0
(150 1250);
DISPLAY 0.638298 (150 1250);
FORCEPROP 1 LAST MATERIAL EMPTY
J 0
(150 1200);
DISPLAY 0.638298 (150 1200);
PAINT RED (150 1200);
FORCEPROP 1 LAST PACK_TYPE 0402
J 0
(150 1100);
DISPLAY 0.638298 (150 1100);
FORCEPROP 1 LAST VOLTAGE 50V
J 0
(150 1300);
DISPLAY 0.638298 (150 1300);
FORCEPROP 1 LAST VALUE 1000PF
J 0
(150 1350);
DISPLAY 0.638298 (150 1350);
FORCEPROP 1 LAST $LOCATION C1975
J 0
(150 1400);
DISPLAY 0.638298 (150 1400);
FORCEPROP 1 LASTPIN (100 1400) $PN 1
J 0
(110 1380);
DISPLAY 0.787234 (110 1380);
PAINT MONO (110 1380);
FORCEPROP 1 LASTPIN (100 1200) $PN 2
J 0
(110 1180);
DISPLAY 0.787234 (110 1180);
PAINT MONO (110 1180);
FORCEPROP 2 LAST CDS_LIB pure_quanta
J 0
(100 1300);
DISPLAY INVISIBLE (100 1300);
FORCEPROP 1 LAST PATH I129
J 0
(150 1450);
DISPLAY 0.978723 (150 1450);
PAINT WHITE (150 1450);
DISPLAY INVISIBLE (150 1450);
FORCEPROP 2 LAST CDS_LOCATION C1975
J 0
(150 1500);
DISPLAY 1.021277 (150 1500);
DISPLAY INVISIBLE (150 1500);
FORCEPROP 2 LAST $SEC 1
J 0
(150 1500);
DISPLAY 0.680851 (150 1500);
PAINT MONO (150 1500);
DISPLAY INVISIBLE (150 1500);
FORCEPROP 2 LAST CDS_SEC 1
J 0
(150 1500);
DISPLAY 1.021277 (150 1500);
DISPLAY INVISIBLE (150 1500);
FORCEADD Q_RES..2
(-2975 2600);
FORCEPROP 1 LAST PART_NUMBER CS41002FB09
J 0
(-2935 2475);
DISPLAY 0.510638 (-2935 2475);
DISPLAY INVISIBLE (-2935 2475);
FORCEPROP 1 LAST WATTAGE 1/16W
J 0
(-2935 2575);
DISPLAY 0.510638 (-2935 2575);
FORCEPROP 1 LAST TOLERANCE 1%
J 0
(-2930 2625);
DISPLAY 0.510638 (-2930 2625);
FORCEPROP 1 LAST VALUE 100K
J 0
(-2930 2675);
DISPLAY 0.510638 (-2930 2675);
FORCEPROP 1 LAST PACK_TYPE 0402LF
J 0
(-2935 2425);
DISPLAY 0.510638 (-2935 2425);
FORCEPROP 1 LAST MATERIAL EMPTY
J 0
(-2935 2525);
DISPLAY 0.510638 (-2935 2525);
PAINT RED (-2935 2525);
FORCEPROP 1 LAST $LOCATION R3429
J 0
(-2930 2725);
DISPLAY 0.978723 (-2930 2725);
FORCEPROP 1 LASTPIN (-2975 2700) $PN 1
J 0
(-2970 2662);
DISPLAY 0.787234 (-2970 2662);
PAINT MONO (-2970 2662);
FORCEPROP 1 LASTPIN (-2975 2500) $PN 2
J 0
(-2970 2510);
DISPLAY 0.787234 (-2970 2510);
PAINT MONO (-2970 2510);
FORCEPROP 2 LAST CDS_LIB pure_quanta
J 0
(-2975 2600);
DISPLAY INVISIBLE (-2975 2600);
FORCEPROP 1 LAST PATH I130
J 0
(-2925 2775);
DISPLAY 0.978723 (-2925 2775);
PAINT WHITE (-2925 2775);
DISPLAY INVISIBLE (-2925 2775);
FORCEPROP 0 LAST CDS_LOCATION R3429
J 0
(-2925 2775);
DISPLAY 1.021277 (-2925 2775);
DISPLAY INVISIBLE (-2925 2775);
FORCEPROP 0 LAST $SEC 1
J 0
(-2925 2775);
DISPLAY 0.680851 (-2925 2775);
PAINT MONO (-2925 2775);
DISPLAY INVISIBLE (-2925 2775);
FORCEPROP 0 LAST CDS_SEC 1
J 0
(-2925 2775);
DISPLAY 1.021277 (-2925 2775);
DISPLAY INVISIBLE (-2925 2775);
FORCEADD Q_RES..2
(-2950 2125);
FORCEPROP 1 LAST PART_NUMBER CS35492FB03
J 0
(-2910 2000);
DISPLAY 0.787234 (-2910 2000);
DISPLAY INVISIBLE (-2910 2000);
FORCEPROP 1 LAST MATERIAL CHIP
J 0
(-2910 2050);
DISPLAY 0.787234 (-2910 2050);
FORCEPROP 1 LAST VALUE 54.9K
J 0
(-2905 2200);
DISPLAY 0.787234 (-2905 2200);
FORCEPROP 1 LAST TOLERANCE 1%
J 0
(-2905 2150);
DISPLAY 0.787234 (-2905 2150);
FORCEPROP 1 LAST WATTAGE 1/16W
J 0
(-2910 2100);
DISPLAY 0.787234 (-2910 2100);
FORCEPROP 1 LAST PACK_TYPE 0402LF
J 0
(-2910 1950);
DISPLAY 0.787234 (-2910 1950);
FORCEPROP 1 LAST $LOCATION R3463
J 0
(-2905 2250);
DISPLAY 0.978723 (-2905 2250);
FORCEPROP 1 LASTPIN (-2950 2225) $PN 1
J 0
(-2945 2187);
DISPLAY 0.787234 (-2945 2187);
PAINT MONO (-2945 2187);
FORCEPROP 1 LASTPIN (-2950 2025) $PN 2
J 0
(-2945 2035);
DISPLAY 0.787234 (-2945 2035);
PAINT MONO (-2945 2035);
FORCEPROP 1 LAST PATH I131
J 0
(-2900 2300);
DISPLAY 0.978723 (-2900 2300);
PAINT WHITE (-2900 2300);
DISPLAY INVISIBLE (-2900 2300);
FORCEPROP 2 LAST CDS_LIB pure_quanta
J 0
(-2950 2125);
DISPLAY INVISIBLE (-2950 2125);
FORCEPROP 0 LAST CDS_LOCATION R3463
J 0
(-2900 2300);
DISPLAY 1.021277 (-2900 2300);
DISPLAY INVISIBLE (-2900 2300);
FORCEPROP 0 LAST $SEC 1
J 0
(-2900 2300);
DISPLAY 0.680851 (-2900 2300);
PAINT MONO (-2900 2300);
DISPLAY INVISIBLE (-2900 2300);
FORCEPROP 0 LAST CDS_SEC 1
J 0
(-2900 2300);
DISPLAY 1.021277 (-2900 2300);
DISPLAY INVISIBLE (-2900 2300);
FORCEADD Q_RES..2
(-2925 1250);
FORCEPROP 1 LAST PART_NUMBER CS31002FB08
J 0
(-2885 1125);
DISPLAY 0.510638 (-2885 1125);
DISPLAY INVISIBLE (-2885 1125);
FORCEPROP 1 LAST MATERIAL CHIP
J 0
(-2885 1175);
DISPLAY 0.510638 (-2885 1175);
FORCEPROP 1 LAST VALUE 10K
J 0
(-2880 1325);
DISPLAY 0.510638 (-2880 1325);
FORCEPROP 1 LAST TOLERANCE 1%
J 0
(-2880 1275);
DISPLAY 0.510638 (-2880 1275);
FORCEPROP 1 LAST PACK_TYPE 0402LF
J 0
(-2885 1075);
DISPLAY 0.510638 (-2885 1075);
FORCEPROP 1 LAST WATTAGE 1/16W
J 0
(-2885 1225);
DISPLAY 0.510638 (-2885 1225);
FORCEPROP 1 LAST $LOCATION R3465
J 0
(-2880 1375);
DISPLAY 0.978723 (-2880 1375);
FORCEPROP 1 LASTPIN (-2925 1350) $PN 1
J 0
(-2920 1312);
DISPLAY 0.787234 (-2920 1312);
PAINT MONO (-2920 1312);
FORCEPROP 1 LASTPIN (-2925 1150) $PN 2
J 0
(-2920 1160);
DISPLAY 0.787234 (-2920 1160);
PAINT MONO (-2920 1160);
FORCEPROP 2 LAST CDS_LIB pure_quanta
J 0
(-2925 1250);
DISPLAY INVISIBLE (-2925 1250);
FORCEPROP 1 LAST PATH I132
J 0
(-2875 1425);
DISPLAY 0.978723 (-2875 1425);
PAINT WHITE (-2875 1425);
DISPLAY INVISIBLE (-2875 1425);
FORCEPROP 0 LAST CDS_LOCATION R3465
J 0
(-2875 1425);
DISPLAY 1.021277 (-2875 1425);
DISPLAY INVISIBLE (-2875 1425);
FORCEPROP 0 LAST $SEC 1
J 0
(-2875 1425);
DISPLAY 0.680851 (-2875 1425);
PAINT MONO (-2875 1425);
DISPLAY INVISIBLE (-2875 1425);
FORCEPROP 0 LAST CDS_SEC 1
J 0
(-2875 1425);
DISPLAY 1.021277 (-2875 1425);
DISPLAY INVISIBLE (-2875 1425);
FORCEADD Q_RES..2
(-2900 775);
FORCEPROP 1 LAST PART_NUMBER CS41002FB09
J 0
(-2860 650);
DISPLAY 0.510638 (-2860 650);
DISPLAY INVISIBLE (-2860 650);
FORCEPROP 1 LAST PACK_TYPE 0402LF
J 0
(-2860 600);
DISPLAY 0.510638 (-2860 600);
FORCEPROP 1 LAST WATTAGE 1/16W
J 0
(-2860 750);
DISPLAY 0.510638 (-2860 750);
FORCEPROP 1 LAST MATERIAL EMPTY
J 0
(-2860 700);
DISPLAY 0.510638 (-2860 700);
PAINT RED (-2860 700);
FORCEPROP 1 LAST VALUE 100K
J 0
(-2855 850);
DISPLAY 0.510638 (-2855 850);
FORCEPROP 1 LAST TOLERANCE 1%
J 0
(-2855 800);
DISPLAY 0.510638 (-2855 800);
FORCEPROP 1 LAST $LOCATION R3431
J 0
(-2855 900);
DISPLAY 0.978723 (-2855 900);
FORCEPROP 1 LASTPIN (-2900 875) $PN 1
J 0
(-2895 837);
DISPLAY 0.787234 (-2895 837);
PAINT MONO (-2895 837);
FORCEPROP 1 LASTPIN (-2900 675) $PN 2
J 0
(-2895 685);
DISPLAY 0.787234 (-2895 685);
PAINT MONO (-2895 685);
FORCEPROP 1 LAST PATH I133
J 0
(-2850 950);
DISPLAY 0.978723 (-2850 950);
PAINT WHITE (-2850 950);
DISPLAY INVISIBLE (-2850 950);
FORCEPROP 2 LAST CDS_LIB pure_quanta
J 0
(-2900 775);
DISPLAY INVISIBLE (-2900 775);
FORCEPROP 0 LAST CDS_LOCATION R3431
J 0
(-2850 950);
DISPLAY 1.021277 (-2850 950);
DISPLAY INVISIBLE (-2850 950);
FORCEPROP 0 LAST $SEC 1
J 0
(-2850 950);
DISPLAY 0.680851 (-2850 950);
PAINT MONO (-2850 950);
DISPLAY INVISIBLE (-2850 950);
FORCEPROP 0 LAST CDS_SEC 1
J 0
(-2850 950);
DISPLAY 1.021277 (-2850 950);
DISPLAY INVISIBLE (-2850 950);
FORCEADD Q_RES..2
(-2975 -375);
FORCEPROP 1 LAST PART_NUMBER CS35492FB03
J 0
(-2935 -500);
DISPLAY 0.787234 (-2935 -500);
DISPLAY INVISIBLE (-2935 -500);
FORCEPROP 1 LAST PACK_TYPE 0402LF
J 0
(-2935 -550);
DISPLAY 0.787234 (-2935 -550);
FORCEPROP 1 LAST WATTAGE 1/16W
J 0
(-2935 -400);
DISPLAY 0.787234 (-2935 -400);
FORCEPROP 1 LAST TOLERANCE 1%
J 0
(-2930 -350);
DISPLAY 0.787234 (-2930 -350);
FORCEPROP 1 LAST MATERIAL CHIP
J 0
(-2935 -450);
DISPLAY 0.787234 (-2935 -450);
FORCEPROP 1 LAST VALUE 54.9K
J 0
(-2930 -300);
DISPLAY 0.787234 (-2930 -300);
FORCEPROP 1 LAST $LOCATION R3464
J 0
(-2930 -250);
DISPLAY 0.978723 (-2930 -250);
FORCEPROP 1 LASTPIN (-2975 -275) $PN 1
J 0
(-2970 -313);
DISPLAY 0.787234 (-2970 -313);
PAINT MONO (-2970 -313);
FORCEPROP 1 LASTPIN (-2975 -475) $PN 2
J 0
(-2970 -465);
DISPLAY 0.787234 (-2970 -465);
PAINT MONO (-2970 -465);
FORCEPROP 2 LAST CDS_LIB pure_quanta
J 0
(-2975 -375);
DISPLAY INVISIBLE (-2975 -375);
FORCEPROP 1 LAST PATH I134
J 0
(-2925 -200);
DISPLAY 0.978723 (-2925 -200);
PAINT WHITE (-2925 -200);
DISPLAY INVISIBLE (-2925 -200);
FORCEPROP 0 LAST CDS_LOCATION R3464
J 0
(-2925 -200);
DISPLAY 1.021277 (-2925 -200);
DISPLAY INVISIBLE (-2925 -200);
FORCEPROP 0 LAST $SEC 1
J 0
(-2925 -200);
DISPLAY 0.680851 (-2925 -200);
PAINT MONO (-2925 -200);
DISPLAY INVISIBLE (-2925 -200);
FORCEPROP 0 LAST CDS_SEC 1
J 0
(-2925 -200);
DISPLAY 1.021277 (-2925 -200);
DISPLAY INVISIBLE (-2925 -200);
FORCEADD MOSFET_NCH_DUAL..1
(3300 4225);
FORCEPROP 1 LAST PART_NUMBER BAM138K0003
J 0
(3451 4139);
DISPLAY 0.723404 (3451 4139);
PAINT GREEN (3451 4139);
DISPLAY INVISIBLE (3451 4139);
FORCEPROP 2 LAST PART_TYPE SMLF
J 0
(3475 4300);
DISPLAY 1.021277 (3475 4300);
FORCEPROP 2 LAST VALUE PJT138K
J 0
(3475 4250);
DISPLAY 1.021277 (3475 4250);
FORCEPROP 1 LAST MATERIAL IC
J 0
(3451 4074);
DISPLAY 0.723404 (3451 4074);
PAINT GREEN (3451 4074);
FORCEPROP 1 LAST $LOCATION Q106
J 0
(3451 4199);
DISPLAY 0.723404 (3451 4199);
PAINT GREEN (3451 4199);
FORCEPROP 0 LASTPIN (3350 4425) $PN 6
R 1
J 0
(3340 4435);
DISPLAY 0.680851 (3340 4435);
PAINT MONO (3340 4435);
FORCEPROP 0 LASTPIN (3100 4175) $PN 2
J 2
(3090 4185);
DISPLAY 0.680851 (3090 4185);
PAINT MONO (3090 4185);
FORCEPROP 0 LASTPIN (3350 4025) $PN 1
R 1
J 2
(3340 4015);
DISPLAY 0.680851 (3340 4015);
PAINT MONO (3340 4015);
FORCEPROP 1 LAST PATH I135
J 0
(3300 4225);
DISPLAY 0.723404 (3300 4225);
PAINT GREEN (3300 4225);
DISPLAY INVISIBLE (3300 4225);
FORCEPROP 1 LAST CDS_LMAN_SYM_OUTLINE -150,150,150,-150
J 0
(3300 4225);
DISPLAY 0.468085 (3300 4225);
PAINT GREEN (3300 4225);
DISPLAY INVISIBLE (3300 4225);
FORCEPROP 1 LAST NEEDS_NO_SIZE TRUE
J 0
(3300 4224);
DISPLAY 0.468085 (3300 4224);
PAINT GREEN (3300 4224);
DISPLAY INVISIBLE (3300 4224);
FORCEPROP 2 LAST CDS_LIB pure_quanta
J 0
(3300 4225);
DISPLAY INVISIBLE (3300 4225);
FORCEPROP 2 LAST CDS_LOCATION Q106
J 0
(3475 4350);
DISPLAY 1.021277 (3475 4350);
DISPLAY INVISIBLE (3475 4350);
FORCEPROP 0 LAST $SEC 1
J 0
(3475 4350);
DISPLAY 0.680851 (3475 4350);
PAINT MONO (3475 4350);
DISPLAY INVISIBLE (3475 4350);
FORCEPROP 2 LAST CDS_SEC 1
J 0
(3475 4350);
DISPLAY 1.021277 (3475 4350);
DISPLAY INVISIBLE (3475 4350);
FORCEADD UNIVERSAL_POWER..1
(2175 4700);
FORCEPROP 3 LASTPIN (2175 4650) SIG_NAME P3V3_AUX\g
J 0
(2185 4660);
DISPLAY 0.659574 (2185 4660);
PAINT MONO (2185 4660);
DISPLAY INVISIBLE (2185 4660);
FORCEPROP 1 LAST HDL_POWER P3V3_AUX
J 1
(2175 4750);
DISPLAY 0.872340 (2175 4750);
PAINT GREEN (2175 4750);
FORCEPROP 1 LAST PATH I138
J 0
(2225 4725);
DISPLAY 0.872340 (2225 4725);
PAINT AQUA (2225 4725);
DISPLAY INVISIBLE (2225 4725);
FORCEPROP 2 LAST CDS_LIB logical_power
J 0
(2175 4700);
PAINT MONO (2175 4700);
DISPLAY INVISIBLE (2175 4700);
FORCEADD UNIVERSAL_GND..1
(3350 3850);
FORCEPROP 3 LASTPIN (3350 3900) SIG_NAME GND\g
J 0
(3360 3910);
DISPLAY 0.659574 (3360 3910);
PAINT MONO (3360 3910);
DISPLAY INVISIBLE (3360 3910);
FORCEPROP 1 LAST HDL_POWER GND
J 1
(3375 3775);
DISPLAY 0.872340 (3375 3775);
PAINT GREEN (3375 3775);
DISPLAY INVISIBLE (3375 3775);
FORCEPROP 1 LAST PATH I139
J 0
(3425 3850);
DISPLAY 0.872340 (3425 3850);
PAINT AQUA (3425 3850);
DISPLAY INVISIBLE (3425 3850);
FORCEPROP 2 LAST CDS_LIB logical_power
J 0
(3350 3850);
DISPLAY INVISIBLE (3350 3850);
FORCEADD OFFPAGE..4
R 2
(1925 4175);
FORCEPROP 2 LAST $XR0 213 
J 0
(1643 4175);
DISPLAY 0.638298 (1643 4175);
PAINT MONO (1643 4175);
FORCEPROP 2 LAST PATH I143
J 0
(1650 4225);
DISPLAY 1.021277 (1650 4225);
DISPLAY INVISIBLE (1650 4225);
FORCEPROP 1 LAST OFFPAGE TRUE
J 2
(1600 4050);
DISPLAY 0.872340 (1600 4050);
PAINT GREEN (1600 4050);
DISPLAY INVISIBLE (1600 4050);
FORCEPROP 1 LAST COMMENT_BODY TRUE
J 2
(1950 4075);
DISPLAY 0.872340 (1950 4075);
PAINT GREEN (1950 4075);
DISPLAY INVISIBLE (1950 4075);
FORCEPROP 2 LAST CDS_LIB standard
J 0
(1925 4175);
DISPLAY INVISIBLE (1925 4175);
FORCEADD Q_RES..2
(2200 3900);
FORCEPROP 1 LAST PART_NUMBER CS31002FB08
J 0
(2240 3775);
DISPLAY 0.510638 (2240 3775);
DISPLAY INVISIBLE (2240 3775);
FORCEPROP 1 LAST MATERIAL CHIP
J 0
(2240 3825);
DISPLAY 0.510638 (2240 3825);
FORCEPROP 1 LAST WATTAGE 1/16W
J 0
(2240 3875);
DISPLAY 0.510638 (2240 3875);
FORCEPROP 1 LAST VALUE 10K
J 0
(2245 3975);
DISPLAY 0.510638 (2245 3975);
FORCEPROP 1 LAST TOLERANCE 1%
J 0
(2245 3925);
DISPLAY 0.510638 (2245 3925);
FORCEPROP 1 LAST PACK_TYPE 0402LF
J 0
(2240 3725);
DISPLAY 0.510638 (2240 3725);
FORCEPROP 1 LAST $LOCATION R3471
J 0
(2245 4025);
DISPLAY 0.978723 (2245 4025);
FORCEPROP 1 LASTPIN (2200 4000) $PN 1
J 0
(2205 3962);
DISPLAY 0.787234 (2205 3962);
PAINT MONO (2205 3962);
FORCEPROP 1 LASTPIN (2200 3800) $PN 2
J 0
(2205 3810);
DISPLAY 0.787234 (2205 3810);
PAINT MONO (2205 3810);
FORCEPROP 2 LAST CDS_LIB pure_quanta
J 0
(2200 3900);
DISPLAY INVISIBLE (2200 3900);
FORCEPROP 1 LAST PATH I144
J 0
(2250 4075);
DISPLAY 0.978723 (2250 4075);
PAINT WHITE (2250 4075);
DISPLAY INVISIBLE (2250 4075);
FORCEPROP 0 LAST CDS_LOCATION R3471
J 0
(2250 4075);
DISPLAY 1.021277 (2250 4075);
DISPLAY INVISIBLE (2250 4075);
FORCEPROP 0 LAST $SEC 1
J 0
(2250 4075);
DISPLAY 0.680851 (2250 4075);
PAINT MONO (2250 4075);
DISPLAY INVISIBLE (2250 4075);
FORCEPROP 0 LAST CDS_SEC 1
J 0
(2250 4075);
DISPLAY 1.021277 (2250 4075);
DISPLAY INVISIBLE (2250 4075);
FORCEADD Q_RES..2
(2175 4450);
FORCEPROP 1 LAST PART_NUMBER CS31002FB08
J 0
(2215 4325);
DISPLAY 0.510638 (2215 4325);
DISPLAY INVISIBLE (2215 4325);
FORCEPROP 1 LAST WATTAGE 1/16W
J 0
(2215 4425);
DISPLAY 0.510638 (2215 4425);
FORCEPROP 1 LAST MATERIAL EMPTY
J 0
(2215 4375);
DISPLAY 0.510638 (2215 4375);
PAINT RED (2215 4375);
FORCEPROP 1 LAST PACK_TYPE 0402LF
J 0
(2215 4275);
DISPLAY 0.510638 (2215 4275);
FORCEPROP 1 LAST TOLERANCE 1%
J 0
(2220 4475);
DISPLAY 0.510638 (2220 4475);
FORCEPROP 1 LAST VALUE 10K
J 0
(2220 4525);
DISPLAY 0.510638 (2220 4525);
FORCEPROP 1 LAST $LOCATION R3470
J 0
(2220 4575);
DISPLAY 0.978723 (2220 4575);
FORCEPROP 1 LASTPIN (2175 4550) $PN 1
J 0
(2180 4512);
DISPLAY 0.787234 (2180 4512);
PAINT MONO (2180 4512);
FORCEPROP 1 LASTPIN (2175 4350) $PN 2
J 0
(2180 4360);
DISPLAY 0.787234 (2180 4360);
PAINT MONO (2180 4360);
FORCEPROP 2 LAST CDS_LIB pure_quanta
J 0
(2175 4450);
DISPLAY INVISIBLE (2175 4450);
FORCEPROP 1 LAST PATH I145
J 0
(2225 4625);
DISPLAY 0.978723 (2225 4625);
PAINT WHITE (2225 4625);
DISPLAY INVISIBLE (2225 4625);
FORCEPROP 0 LAST CDS_LOCATION R3470
J 0
(2225 4625);
DISPLAY 1.021277 (2225 4625);
DISPLAY INVISIBLE (2225 4625);
FORCEPROP 0 LAST $SEC 1
J 0
(2225 4625);
DISPLAY 0.680851 (2225 4625);
PAINT MONO (2225 4625);
DISPLAY INVISIBLE (2225 4625);
FORCEPROP 0 LAST CDS_SEC 1
J 0
(2225 4625);
DISPLAY 1.021277 (2225 4625);
DISPLAY INVISIBLE (2225 4625);
FORCEADD UNIVERSAL_GND..1
(2200 3625);
FORCEPROP 3 LASTPIN (2200 3675) SIG_NAME GND\g
J 0
(2210 3685);
DISPLAY 0.659574 (2210 3685);
PAINT MONO (2210 3685);
DISPLAY INVISIBLE (2210 3685);
FORCEPROP 1 LAST HDL_POWER GND
J 1
(2225 3550);
DISPLAY 0.872340 (2225 3550);
PAINT GREEN (2225 3550);
DISPLAY INVISIBLE (2225 3550);
FORCEPROP 1 LAST PATH I146
J 0
(2275 3625);
DISPLAY 0.872340 (2275 3625);
PAINT AQUA (2275 3625);
DISPLAY INVISIBLE (2275 3625);
FORCEPROP 2 LAST CDS_LIB logical_power
J 0
(2200 3625);
DISPLAY INVISIBLE (2200 3625);
FORCEADD Q_RES..1
R 1
(4200 4175);
FORCEPROP 1 LAST PART_NUMBER CS00002JB13
J 0
(4250 4275);
DISPLAY 0.638298 (4250 4275);
DISPLAY INVISIBLE (4250 4275);
FORCEPROP 1 LAST MATERIAL EMPTY
J 0
(4275 4025);
DISPLAY 0.638298 (4275 4025);
PAINT RED (4275 4025);
FORCEPROP 1 LAST PACK_TYPE 0402LF
J 0
(4275 4125);
DISPLAY 0.638298 (4275 4125);
FORCEPROP 1 LAST TOLERANCE 5%
J 0
(4275 4075);
DISPLAY 0.638298 (4275 4075);
FORCEPROP 1 LAST VALUE 0
J 2
(4300 4225);
DISPLAY 0.638298 (4300 4225);
FORCEPROP 1 LAST $LOCATION R3472
J 0
(4250 4175);
DISPLAY 0.787234 (4250 4175);
FORCEPROP 1 LASTPIN (4200 4075) $PN 1
R 1
J 0
(4188 4087);
DISPLAY 0.787234 (4188 4087);
PAINT MONO (4188 4087);
FORCEPROP 1 LASTPIN (4200 4275) $PN 2
R 1
J 0
(4188 4237);
DISPLAY 0.787234 (4188 4237);
PAINT MONO (4188 4237);
FORCEPROP 1 LAST WATTAGE 1/16W
R 1
J 2
(4075 4350);
DISPLAY 0.638298 (4075 4350);
DISPLAY INVISIBLE (4075 4350);
FORCEPROP 1 LAST PATH I147
R 1
J 0
(4050 4125);
DISPLAY 0.978723 (4050 4125);
PAINT WHITE (4050 4125);
DISPLAY INVISIBLE (4050 4125);
FORCEPROP 2 LAST CDS_LIB pure_quanta
R 1
J 0
(4200 4175);
DISPLAY INVISIBLE (4200 4175);
FORCEPROP 0 LAST CDS_LOCATION R3472
R 1
J 0
(4250 4325);
DISPLAY 1.021277 (4250 4325);
DISPLAY INVISIBLE (4250 4325);
FORCEPROP 0 LAST $SEC 1
R 1
J 0
(4250 4325);
DISPLAY 0.680851 (4250 4325);
PAINT MONO (4250 4325);
DISPLAY INVISIBLE (4250 4325);
FORCEPROP 0 LAST CDS_SEC 1
R 1
J 0
(4250 4325);
DISPLAY 1.021277 (4250 4325);
DISPLAY INVISIBLE (4250 4325);
FORCEADD UNIVERSAL_GND..1
(4200 3900);
FORCEPROP 3 LASTPIN (4200 3950) SIG_NAME GND\g
J 0
(4210 3960);
DISPLAY 0.659574 (4210 3960);
PAINT MONO (4210 3960);
DISPLAY INVISIBLE (4210 3960);
FORCEPROP 2 LAST CDS_LIB logical_power
J 0
(4200 3900);
DISPLAY INVISIBLE (4200 3900);
FORCEPROP 1 LAST PATH I148
J 0
(4275 3900);
DISPLAY 0.872340 (4275 3900);
PAINT AQUA (4275 3900);
DISPLAY INVISIBLE (4275 3900);
FORCEPROP 1 LAST HDL_POWER GND
J 1
(4225 3825);
DISPLAY 0.872340 (4225 3825);
PAINT GREEN (4225 3825);
DISPLAY INVISIBLE (4225 3825);
FORCEADD OFFPAGE..2
(4300 4475);
FORCEPROP 2 LAST $XR0 136 
J 0
(4489 4475);
DISPLAY 0.638298 (4489 4475);
PAINT MONO (4489 4475);
FORCEPROP 2 LAST CDS_LIB standard
J 0
(4300 4475);
DISPLAY INVISIBLE (4300 4475);
FORCEPROP 2 LAST PATH I149
J 0
(4475 4550);
DISPLAY 1.021277 (4475 4550);
DISPLAY INVISIBLE (4475 4550);
FORCEPROP 1 LAST COMMENT_BODY TRUE
J 0
(4255 4380);
DISPLAY 0.872340 (4255 4380);
PAINT GREEN (4255 4380);
DISPLAY INVISIBLE (4255 4380);
FORCEPROP 1 LAST OFFPAGE TRUE
J 0
(4625 4350);
DISPLAY 0.872340 (4625 4350);
PAINT AQUA (4625 4350);
DISPLAY INVISIBLE (4625 4350);
FORCEADD UNIVERSAL_POWER..1
(-2975 2850);
FORCEPROP 3 LASTPIN (-2975 2800) SIG_NAME P3V3_AUX\g
J 0
(-2965 2810);
DISPLAY 0.659574 (-2965 2810);
PAINT MONO (-2965 2810);
DISPLAY INVISIBLE (-2965 2810);
FORCEPROP 1 LAST HDL_POWER P3V3_AUX
J 1
(-2975 2900);
DISPLAY 0.872340 (-2975 2900);
PAINT GREEN (-2975 2900);
FORCEPROP 2 LAST CDS_LIB logical_power
J 0
(-2975 2850);
PAINT MONO (-2975 2850);
DISPLAY INVISIBLE (-2975 2850);
FORCEPROP 1 LAST PATH I15
J 0
(-2925 2875);
DISPLAY 0.872340 (-2925 2875);
PAINT AQUA (-2925 2875);
DISPLAY INVISIBLE (-2925 2875);
FORCEADD UNIVERSAL_POWER..1
(3900 3575);
FORCEPROP 3 LASTPIN (3900 3525) SIG_NAME P3V3_AUX\g
J 0
(3910 3535);
DISPLAY 0.659574 (3910 3535);
PAINT MONO (3910 3535);
DISPLAY INVISIBLE (3910 3535);
FORCEPROP 1 LAST HDL_POWER P3V3_AUX
J 1
(3900 3625);
DISPLAY 0.872340 (3900 3625);
PAINT GREEN (3900 3625);
FORCEPROP 1 LAST PATH I150
J 0
(3950 3600);
DISPLAY 0.872340 (3950 3600);
PAINT AQUA (3950 3600);
DISPLAY INVISIBLE (3950 3600);
FORCEPROP 2 LAST CDS_LIB logical_power
J 0
(3900 3575);
DISPLAY INVISIBLE (3900 3575);
FORCEADD OFFPAGE..2
(5075 3050);
FORCEPROP 2 LAST $XR1 227 
J 0
(5264 3014);
DISPLAY 0.638298 (5264 3014);
PAINT MONO (5264 3014);
FORCEPROP 2 LAST $XR0 213 
J 0
(5264 3050);
DISPLAY 0.638298 (5264 3050);
PAINT MONO (5264 3050);
FORCEPROP 2 LAST CDS_LIB standard
J 0
(5075 3050);
DISPLAY INVISIBLE (5075 3050);
FORCEPROP 2 LAST PATH I151
J 0
(5250 3125);
DISPLAY 1.021277 (5250 3125);
DISPLAY INVISIBLE (5250 3125);
FORCEPROP 1 LAST COMMENT_BODY TRUE
J 0
(5030 2955);
DISPLAY 0.872340 (5030 2955);
PAINT GREEN (5030 2955);
DISPLAY INVISIBLE (5030 2955);
FORCEPROP 1 LAST OFFPAGE TRUE
J 0
(5400 2925);
DISPLAY 0.872340 (5400 2925);
PAINT AQUA (5400 2925);
DISPLAY INVISIBLE (5400 2925);
FORCEADD Q_CAP..1
(4800 2650);
FORCEPROP 1 LAST PART_NUMBER TMP_QCH21006JB10
J 0
(4850 2500);
DISPLAY 0.638298 (4850 2500);
DISPLAY INVISIBLE (4850 2500);
FORCEPROP 1 LAST MATERIAL EMPTY
J 0
(4850 2550);
DISPLAY 0.638298 (4850 2550);
PAINT RED (4850 2550);
FORCEPROP 1 LAST PACK_TYPE 0402
J 0
(4850 2450);
DISPLAY 0.638298 (4850 2450);
FORCEPROP 1 LAST VALUE 1000PF
J 0
(4850 2700);
DISPLAY 0.638298 (4850 2700);
FORCEPROP 1 LAST VOLTAGE 50V
J 0
(4850 2650);
DISPLAY 0.638298 (4850 2650);
FORCEPROP 1 LAST TOLERANCE 5%
J 0
(4850 2600);
DISPLAY 0.638298 (4850 2600);
FORCEPROP 1 LAST $LOCATION C1978
J 0
(4850 2750);
DISPLAY 0.638298 (4850 2750);
FORCEPROP 1 LASTPIN (4800 2750) $PN 1
J 0
(4810 2730);
DISPLAY 0.787234 (4810 2730);
PAINT MONO (4810 2730);
FORCEPROP 1 LASTPIN (4800 2550) $PN 2
J 0
(4810 2530);
DISPLAY 0.787234 (4810 2530);
PAINT MONO (4810 2530);
FORCEPROP 1 LAST PATH I152
J 0
(4850 2800);
DISPLAY 0.978723 (4850 2800);
PAINT WHITE (4850 2800);
DISPLAY INVISIBLE (4850 2800);
FORCEPROP 2 LAST CDS_LIB pure_quanta
J 0
(4800 2650);
DISPLAY INVISIBLE (4800 2650);
FORCEPROP 2 LAST CDS_LOCATION C1978
J 0
(4850 2850);
DISPLAY 1.021277 (4850 2850);
DISPLAY INVISIBLE (4850 2850);
FORCEPROP 2 LAST $SEC 1
J 0
(4850 2850);
DISPLAY 0.680851 (4850 2850);
PAINT MONO (4850 2850);
DISPLAY INVISIBLE (4850 2850);
FORCEPROP 2 LAST CDS_SEC 1
J 0
(4850 2850);
DISPLAY 1.021277 (4850 2850);
DISPLAY INVISIBLE (4850 2850);
FORCEADD UNIVERSAL_GND..1
(4800 2450);
FORCEPROP 3 LASTPIN (4800 2500) SIG_NAME GND\g
J 0
(4810 2510);
DISPLAY 0.659574 (4810 2510);
PAINT MONO (4810 2510);
DISPLAY INVISIBLE (4810 2510);
FORCEPROP 1 LAST PATH I153
J 0
(4875 2450);
DISPLAY 0.872340 (4875 2450);
PAINT AQUA (4875 2450);
DISPLAY INVISIBLE (4875 2450);
FORCEPROP 2 LAST CDS_LIB logical_power
J 0
(4800 2450);
DISPLAY INVISIBLE (4800 2450);
FORCEPROP 1 LAST HDL_POWER GND
J 1
(4825 2375);
DISPLAY 0.872340 (4825 2375);
PAINT GREEN (4825 2375);
DISPLAY INVISIBLE (4825 2375);
FORCEADD Q_RES..2
(3900 3275);
FORCEPROP 1 LAST PART_NUMBER CS24702JB10
J 0
(3940 3100);
DISPLAY 0.638298 (3940 3100);
DISPLAY INVISIBLE (3940 3100);
FORCEPROP 1 LAST TOLERANCE 5%
J 0
(3945 3300);
DISPLAY 0.638298 (3945 3300);
FORCEPROP 1 LAST VALUE 4.7K
J 0
(3945 3350);
DISPLAY 0.638298 (3945 3350);
FORCEPROP 1 LAST PACK_TYPE 0402LF
J 0
(3940 3150);
DISPLAY 0.638298 (3940 3150);
FORCEPROP 1 LAST MATERIAL CHIP
J 0
(3940 3200);
DISPLAY 0.638298 (3940 3200);
FORCEPROP 1 LAST WATTAGE 1/16W
J 0
(3940 3250);
DISPLAY 0.638298 (3940 3250);
FORCEPROP 1 LAST $LOCATION R3475
J 0
(3945 3400);
DISPLAY 0.978723 (3945 3400);
FORCEPROP 1 LASTPIN (3900 3375) $PN 1
J 0
(3905 3337);
DISPLAY 0.787234 (3905 3337);
PAINT MONO (3905 3337);
FORCEPROP 1 LASTPIN (3900 3175) $PN 2
J 0
(3905 3185);
DISPLAY 0.787234 (3905 3185);
PAINT MONO (3905 3185);
FORCEPROP 1 LAST PATH I154
J 0
(3950 3450);
DISPLAY 0.978723 (3950 3450);
PAINT WHITE (3950 3450);
DISPLAY INVISIBLE (3950 3450);
FORCEPROP 2 LAST CDS_LIB pure_quanta
J 0
(3900 3275);
DISPLAY INVISIBLE (3900 3275);
FORCEPROP 0 LAST CDS_LOCATION R3475
J 0
(3950 3450);
DISPLAY 1.021277 (3950 3450);
DISPLAY INVISIBLE (3950 3450);
FORCEPROP 0 LAST $SEC 1
J 0
(3950 3450);
DISPLAY 0.680851 (3950 3450);
PAINT MONO (3950 3450);
DISPLAY INVISIBLE (3950 3450);
FORCEPROP 0 LAST CDS_SEC 1
J 0
(3950 3450);
DISPLAY 1.021277 (3950 3450);
DISPLAY INVISIBLE (3950 3450);
FORCEADD UNIVERSAL_POWER..1
(2975 3325);
FORCEPROP 3 LASTPIN (2975 3275) SIG_NAME P3V3_AUX\g
J 0
(2985 3285);
DISPLAY 0.659574 (2985 3285);
PAINT MONO (2985 3285);
DISPLAY INVISIBLE (2985 3285);
FORCEPROP 1 LAST HDL_POWER P3V3_AUX
J 1
(2975 3375);
DISPLAY 0.872340 (2975 3375);
PAINT GREEN (2975 3375);
FORCEPROP 1 LAST PATH I155
J 0
(3025 3350);
DISPLAY 0.872340 (3025 3350);
PAINT AQUA (3025 3350);
DISPLAY INVISIBLE (3025 3350);
FORCEPROP 2 LAST CDS_LIB logical_power
J 0
(2975 3325);
PAINT MONO (2975 3325);
DISPLAY INVISIBLE (2975 3325);
FORCEADD UNIVERSAL_GND..1
(3900 2450);
FORCEPROP 3 LASTPIN (3900 2500) SIG_NAME GND\g
J 0
(3910 2510);
DISPLAY 0.659574 (3910 2510);
PAINT MONO (3910 2510);
DISPLAY INVISIBLE (3910 2510);
FORCEPROP 1 LAST PATH I156
J 0
(3975 2450);
DISPLAY 0.872340 (3975 2450);
PAINT AQUA (3975 2450);
DISPLAY INVISIBLE (3975 2450);
FORCEPROP 2 LAST CDS_LIB logical_power
J 0
(3900 2450);
DISPLAY INVISIBLE (3900 2450);
FORCEPROP 1 LAST HDL_POWER GND
J 1
(3925 2375);
DISPLAY 0.872340 (3925 2375);
PAINT GREEN (3925 2375);
DISPLAY INVISIBLE (3925 2375);
FORCEADD MOSFET_NCH_DUAL..2
(3850 2825);
FORCEPROP 1 LAST PART_NUMBER BAM138K0003
J 0
(4001 2731);
DISPLAY 0.723404 (4001 2731);
PAINT GREEN (4001 2731);
DISPLAY INVISIBLE (4001 2731);
FORCEPROP 2 LAST PART_TYPE SMLF
J 0
(4025 2900);
DISPLAY 1.021277 (4025 2900);
FORCEPROP 2 LAST VALUE PJT138K
J 0
(4025 2850);
DISPLAY 1.021277 (4025 2850);
FORCEPROP 1 LAST MATERIAL IC
J 0
(4001 2676);
DISPLAY 0.723404 (4001 2676);
PAINT GREEN (4001 2676);
FORCEPROP 1 LAST LOCATION Q107
J 0
(4001 2801);
DISPLAY 0.723404 (4001 2801);
PAINT GREEN (4001 2801);
FORCEPROP 0 LASTPIN (3900 3025) $PN 3
R 1
J 0
(3890 3035);
DISPLAY 0.680851 (3890 3035);
PAINT MONO (3890 3035);
FORCEPROP 0 LASTPIN (3650 2775) $PN 5
J 2
(3640 2785);
DISPLAY 0.680851 (3640 2785);
PAINT MONO (3640 2785);
FORCEPROP 0 LASTPIN (3900 2625) $PN 4
R 1
J 2
(3890 2615);
DISPLAY 0.680851 (3890 2615);
PAINT MONO (3890 2615);
FORCEPROP 1 LAST PATH I157
J 0
(4000 2675);
DISPLAY 0.723404 (4000 2675);
PAINT GREEN (4000 2675);
DISPLAY INVISIBLE (4000 2675);
FORCEPROP 2 LAST CDS_LIB pure_quanta
J 0
(3850 2825);
DISPLAY INVISIBLE (3850 2825);
FORCEPROP 1 LAST NEEDS_NO_SIZE TRUE
J 0
(4000 2716);
DISPLAY 0.468085 (4000 2716);
PAINT GREEN (4000 2716);
DISPLAY INVISIBLE (4000 2716);
FORCEPROP 1 LAST CDS_LMAN_SYM_OUTLINE -150,150,150,-150
J 0
(3850 2825);
DISPLAY 0.468085 (3850 2825);
PAINT GREEN (3850 2825);
DISPLAY INVISIBLE (3850 2825);
FORCEPROP 0 LAST $SEC 2
J 0
(4025 2950);
DISPLAY 0.680851 (4025 2950);
PAINT MONO (4025 2950);
DISPLAY INVISIBLE (4025 2950);
FORCEPROP 0 LAST CDS_SEC 2
J 0
(4025 2950);
DISPLAY 1.021277 (4025 2950);
DISPLAY INVISIBLE (4025 2950);
FORCEADD Q_RES..2
(2975 3025);
FORCEPROP 1 LAST PART_NUMBER CS24702JB10
J 0
(3015 2850);
DISPLAY 0.638298 (3015 2850);
DISPLAY INVISIBLE (3015 2850);
FORCEPROP 1 LAST WATTAGE 1/16W
J 0
(3015 3000);
DISPLAY 0.638298 (3015 3000);
FORCEPROP 1 LAST VALUE 4.7K
J 0
(3020 3100);
DISPLAY 0.638298 (3020 3100);
FORCEPROP 1 LAST TOLERANCE 5%
J 0
(3020 3050);
DISPLAY 0.638298 (3020 3050);
FORCEPROP 1 LAST PACK_TYPE 0402LF
J 0
(3015 2900);
DISPLAY 0.638298 (3015 2900);
FORCEPROP 1 LAST MATERIAL CHIP
J 0
(3015 2950);
DISPLAY 0.638298 (3015 2950);
FORCEPROP 1 LAST $LOCATION R3474
J 0
(3020 3150);
DISPLAY 0.638298 (3020 3150);
FORCEPROP 1 LASTPIN (2975 3125) $PN 1
J 0
(2980 3087);
DISPLAY 0.787234 (2980 3087);
FORCEPROP 1 LASTPIN (2975 2925) $PN 2
J 0
(2980 2935);
DISPLAY 0.787234 (2980 2935);
FORCEPROP 1 LAST PATH I158
J 0
(3025 3200);
DISPLAY 0.978723 (3025 3200);
PAINT WHITE (3025 3200);
DISPLAY INVISIBLE (3025 3200);
FORCEPROP 2 LAST CDS_LIB pure_quanta
J 0
(2975 3025);
PAINT MONO (2975 3025);
DISPLAY INVISIBLE (2975 3025);
FORCEPROP 2 LAST CDS_LOCATION R3474
J 0
(3025 3250);
DISPLAY 1.021277 (3025 3250);
DISPLAY INVISIBLE (3025 3250);
FORCEPROP 2 LAST $SEC 1
J 0
(3025 3250);
DISPLAY 0.680851 (3025 3250);
PAINT MONO (3025 3250);
DISPLAY INVISIBLE (3025 3250);
FORCEPROP 2 LAST CDS_SEC 1
J 0
(3025 3250);
DISPLAY 1.021277 (3025 3250);
DISPLAY INVISIBLE (3025 3250);
FORCEADD UNIVERSAL_GND..1
(2975 2175);
FORCEPROP 3 LASTPIN (2975 2225) SIG_NAME GND\g
J 0
(2985 2235);
DISPLAY 0.659574 (2985 2235);
PAINT MONO (2985 2235);
DISPLAY INVISIBLE (2985 2235);
FORCEPROP 1 LAST PATH I159
J 0
(3050 2175);
DISPLAY 0.872340 (3050 2175);
PAINT AQUA (3050 2175);
DISPLAY INVISIBLE (3050 2175);
FORCEPROP 1 LAST HDL_POWER GND
J 1
(3000 2100);
DISPLAY 0.872340 (3000 2100);
PAINT GREEN (3000 2100);
DISPLAY INVISIBLE (3000 2100);
FORCEPROP 2 LAST CDS_LIB logical_power
J 0
(2975 2175);
DISPLAY INVISIBLE (2975 2175);
FORCEADD UNIVERSAL_GND..1
(-2975 3325);
FORCEPROP 3 LASTPIN (-2975 3375) SIG_NAME GND\g
J 0
(-2965 3385);
DISPLAY 0.659574 (-2965 3385);
PAINT MONO (-2965 3385);
DISPLAY INVISIBLE (-2965 3385);
FORCEPROP 2 LAST CDS_LIB logical_power
J 0
(-2975 3325);
DISPLAY INVISIBLE (-2975 3325);
FORCEPROP 1 LAST HDL_POWER GND
J 1
(-2950 3250);
DISPLAY 0.872340 (-2950 3250);
PAINT GREEN (-2950 3250);
DISPLAY INVISIBLE (-2950 3250);
FORCEPROP 1 LAST PATH I16
J 0
(-2900 3325);
DISPLAY 0.872340 (-2900 3325);
PAINT AQUA (-2900 3325);
DISPLAY INVISIBLE (-2900 3325);
FORCEADD MOSFET_NCH_DUAL..1
(2925 2550);
FORCEPROP 1 LAST PART_NUMBER BAM138K0003
J 0
(3076 2464);
DISPLAY 0.723404 (3076 2464);
PAINT GREEN (3076 2464);
DISPLAY INVISIBLE (3076 2464);
FORCEPROP 2 LAST PART_TYPE SMLF
J 0
(3100 2625);
DISPLAY 1.021277 (3100 2625);
FORCEPROP 2 LAST VALUE PJT138K
J 0
(3100 2575);
DISPLAY 1.021277 (3100 2575);
FORCEPROP 1 LAST MATERIAL IC
J 0
(3076 2399);
DISPLAY 0.723404 (3076 2399);
PAINT GREEN (3076 2399);
FORCEPROP 1 LAST $LOCATION Q107
J 0
(3076 2524);
DISPLAY 0.723404 (3076 2524);
PAINT GREEN (3076 2524);
FORCEPROP 0 LASTPIN (2975 2750) $PN 6
R 1
J 0
(2965 2760);
DISPLAY 0.680851 (2965 2760);
PAINT MONO (2965 2760);
FORCEPROP 0 LASTPIN (2725 2500) $PN 2
J 2
(2715 2510);
DISPLAY 0.680851 (2715 2510);
PAINT MONO (2715 2510);
FORCEPROP 0 LASTPIN (2975 2350) $PN 1
R 1
J 2
(2965 2340);
DISPLAY 0.680851 (2965 2340);
PAINT MONO (2965 2340);
FORCEPROP 1 LAST PATH I160
J 0
(2925 2550);
DISPLAY 0.723404 (2925 2550);
PAINT GREEN (2925 2550);
DISPLAY INVISIBLE (2925 2550);
FORCEPROP 2 LAST CDS_LIB pure_quanta
J 0
(2925 2550);
DISPLAY INVISIBLE (2925 2550);
FORCEPROP 1 LAST NEEDS_NO_SIZE TRUE
J 0
(2925 2549);
DISPLAY 0.468085 (2925 2549);
PAINT GREEN (2925 2549);
DISPLAY INVISIBLE (2925 2549);
FORCEPROP 1 LAST CDS_LMAN_SYM_OUTLINE -150,150,150,-150
J 0
(2925 2550);
DISPLAY 0.468085 (2925 2550);
PAINT GREEN (2925 2550);
DISPLAY INVISIBLE (2925 2550);
FORCEPROP 0 LAST CDS_LOCATION Q107
J 0
(3100 2675);
DISPLAY 1.021277 (3100 2675);
DISPLAY INVISIBLE (3100 2675);
FORCEPROP 0 LAST $SEC 1
J 0
(3100 2675);
DISPLAY 0.680851 (3100 2675);
PAINT MONO (3100 2675);
DISPLAY INVISIBLE (3100 2675);
FORCEPROP 2 LAST CDS_SEC 1
J 0
(3100 2675);
DISPLAY 1.021277 (3100 2675);
DISPLAY INVISIBLE (3100 2675);
FORCEADD UNIVERSAL_POWER..1
(1725 3025);
FORCEPROP 3 LASTPIN (1725 2975) SIG_NAME P3V3_AUX\g
J 0
(1735 2985);
DISPLAY 0.659574 (1735 2985);
PAINT MONO (1735 2985);
DISPLAY INVISIBLE (1735 2985);
FORCEPROP 1 LAST HDL_POWER P3V3_AUX
J 1
(1725 3075);
DISPLAY 0.872340 (1725 3075);
PAINT GREEN (1725 3075);
FORCEPROP 1 LAST PATH I161
J 0
(1775 3050);
DISPLAY 0.872340 (1775 3050);
PAINT AQUA (1775 3050);
DISPLAY INVISIBLE (1775 3050);
FORCEPROP 2 LAST CDS_LIB logical_power
J 0
(1725 3025);
PAINT MONO (1725 3025);
DISPLAY INVISIBLE (1725 3025);
FORCEADD Q_RES..2
(1750 2300);
FORCEPROP 1 LAST PART_NUMBER CS41002FB09
J 0
(1790 2175);
DISPLAY 0.510638 (1790 2175);
DISPLAY INVISIBLE (1790 2175);
FORCEPROP 1 LAST MATERIAL EMPTY
J 0
(1790 2225);
DISPLAY 0.510638 (1790 2225);
PAINT RED (1790 2225);
FORCEPROP 1 LAST WATTAGE 1/16W
J 0
(1790 2275);
DISPLAY 0.510638 (1790 2275);
FORCEPROP 1 LAST TOLERANCE 1%
J 0
(1795 2325);
DISPLAY 0.510638 (1795 2325);
FORCEPROP 1 LAST VALUE 100K
J 0
(1795 2375);
DISPLAY 0.510638 (1795 2375);
FORCEPROP 1 LAST PACK_TYPE 0402LF
J 0
(1790 2125);
DISPLAY 0.510638 (1790 2125);
FORCEPROP 1 LAST $LOCATION R3473
J 0
(1795 2425);
DISPLAY 0.978723 (1795 2425);
FORCEPROP 1 LASTPIN (1750 2400) $PN 1
J 0
(1755 2362);
DISPLAY 0.787234 (1755 2362);
PAINT MONO (1755 2362);
FORCEPROP 1 LASTPIN (1750 2200) $PN 2
J 0
(1755 2210);
DISPLAY 0.787234 (1755 2210);
PAINT MONO (1755 2210);
FORCEPROP 2 LAST CDS_LIB pure_quanta
J 0
(1750 2300);
DISPLAY INVISIBLE (1750 2300);
FORCEPROP 1 LAST PATH I163
J 0
(1800 2475);
DISPLAY 0.978723 (1800 2475);
PAINT WHITE (1800 2475);
DISPLAY INVISIBLE (1800 2475);
FORCEPROP 0 LAST CDS_LOCATION R3473
J 0
(1800 2475);
DISPLAY 1.021277 (1800 2475);
DISPLAY INVISIBLE (1800 2475);
FORCEPROP 0 LAST $SEC 1
J 0
(1800 2475);
DISPLAY 0.680851 (1800 2475);
PAINT MONO (1800 2475);
DISPLAY INVISIBLE (1800 2475);
FORCEPROP 0 LAST CDS_SEC 1
J 0
(1800 2475);
DISPLAY 1.021277 (1800 2475);
DISPLAY INVISIBLE (1800 2475);
FORCEADD UNIVERSAL_GND..1
(1750 2100);
FORCEPROP 3 LASTPIN (1750 2150) SIG_NAME GND\g
J 0
(1760 2160);
DISPLAY 0.659574 (1760 2160);
PAINT MONO (1760 2160);
DISPLAY INVISIBLE (1760 2160);
FORCEPROP 2 LAST CDS_LIB logical_power
J 0
(1750 2100);
DISPLAY INVISIBLE (1750 2100);
FORCEPROP 1 LAST HDL_POWER GND
J 1
(1775 2025);
DISPLAY 0.872340 (1775 2025);
PAINT GREEN (1775 2025);
DISPLAY INVISIBLE (1775 2025);
FORCEPROP 1 LAST PATH I164
J 0
(1825 2100);
DISPLAY 0.872340 (1825 2100);
PAINT AQUA (1825 2100);
DISPLAY INVISIBLE (1825 2100);
FORCEADD OFFPAGE..4
R 2
(1450 2500);
FORCEPROP 2 LAST $XR0 142 
J 0
(1198 2500);
DISPLAY 0.638298 (1198 2500);
PAINT MONO (1198 2500);
FORCEPROP 2 LAST PATH I165
J 0
(1175 2550);
DISPLAY 1.021277 (1175 2550);
DISPLAY INVISIBLE (1175 2550);
FORCEPROP 1 LAST OFFPAGE TRUE
J 2
(1125 2375);
DISPLAY 0.872340 (1125 2375);
PAINT GREEN (1125 2375);
DISPLAY INVISIBLE (1125 2375);
FORCEPROP 1 LAST COMMENT_BODY TRUE
J 2
(1475 2400);
DISPLAY 0.872340 (1475 2400);
PAINT GREEN (1475 2400);
DISPLAY INVISIBLE (1475 2400);
FORCEPROP 2 LAST CDS_LIB standard
J 0
(1450 2500);
DISPLAY INVISIBLE (1450 2500);
FORCEADD Q_RES..2
(1725 2725);
FORCEPROP 1 LAST PART_NUMBER CS31002FB08
J 0
(1765 2600);
DISPLAY 0.510638 (1765 2600);
DISPLAY INVISIBLE (1765 2600);
FORCEPROP 1 LAST TOLERANCE 1%
J 0
(1770 2750);
DISPLAY 0.510638 (1770 2750);
FORCEPROP 1 LAST MATERIAL CHIP
J 0
(1765 2650);
DISPLAY 0.510638 (1765 2650);
FORCEPROP 1 LAST WATTAGE 1/16W
J 0
(1765 2700);
DISPLAY 0.510638 (1765 2700);
FORCEPROP 1 LAST VALUE 10K
J 0
(1770 2800);
DISPLAY 0.510638 (1770 2800);
FORCEPROP 1 LAST PACK_TYPE 0402LF
J 0
(1765 2550);
DISPLAY 0.510638 (1765 2550);
FORCEPROP 1 LAST $LOCATION R3487
J 0
(1770 2850);
DISPLAY 0.978723 (1770 2850);
FORCEPROP 1 LASTPIN (1725 2825) $PN 1
J 0
(1730 2787);
DISPLAY 0.787234 (1730 2787);
PAINT MONO (1730 2787);
FORCEPROP 1 LASTPIN (1725 2625) $PN 2
J 0
(1730 2635);
DISPLAY 0.787234 (1730 2635);
PAINT MONO (1730 2635);
FORCEPROP 1 LAST PATH I166
J 0
(1775 2900);
DISPLAY 0.978723 (1775 2900);
PAINT WHITE (1775 2900);
DISPLAY INVISIBLE (1775 2900);
FORCEPROP 2 LAST CDS_LIB pure_quanta
J 0
(1725 2725);
DISPLAY INVISIBLE (1725 2725);
FORCEPROP 0 LAST CDS_LOCATION R3487
J 0
(1775 2900);
DISPLAY 1.021277 (1775 2900);
DISPLAY INVISIBLE (1775 2900);
FORCEPROP 0 LAST $SEC 1
J 0
(1775 2900);
DISPLAY 0.680851 (1775 2900);
PAINT MONO (1775 2900);
DISPLAY INVISIBLE (1775 2900);
FORCEPROP 0 LAST CDS_SEC 1
J 0
(1775 2900);
DISPLAY 1.021277 (1775 2900);
DISPLAY INVISIBLE (1775 2900);
FORCEADD Q_RES..2
(-3000 4000);
FORCEPROP 1 LAST PART_NUMBER CS35492FB03
J 0
(-2960 3875);
DISPLAY 0.787234 (-2960 3875);
DISPLAY INVISIBLE (-2960 3875);
FORCEPROP 1 LAST VALUE 54.9K
J 0
(-2955 4075);
DISPLAY 0.787234 (-2955 4075);
FORCEPROP 1 LAST TOLERANCE 1%
J 0
(-2955 4025);
DISPLAY 0.787234 (-2955 4025);
FORCEPROP 1 LAST MATERIAL CHIP
J 0
(-2960 3925);
DISPLAY 0.787234 (-2960 3925);
FORCEPROP 1 LAST WATTAGE 1/16W
J 0
(-2960 3975);
DISPLAY 0.787234 (-2960 3975);
FORCEPROP 1 LAST PACK_TYPE 0402LF
J 0
(-2960 3825);
DISPLAY 0.787234 (-2960 3825);
FORCEPROP 1 LAST $LOCATION R3498
J 0
(-2955 4125);
DISPLAY 0.978723 (-2955 4125);
FORCEPROP 1 LASTPIN (-3000 4100) $PN 1
J 0
(-2995 4062);
DISPLAY 0.787234 (-2995 4062);
PAINT MONO (-2995 4062);
FORCEPROP 1 LASTPIN (-3000 3900) $PN 2
J 0
(-2995 3910);
DISPLAY 0.787234 (-2995 3910);
PAINT MONO (-2995 3910);
FORCEPROP 2 LAST CDS_LIB pure_quanta
J 0
(-3000 4000);
DISPLAY INVISIBLE (-3000 4000);
FORCEPROP 1 LAST PATH I167
J 0
(-2950 4175);
DISPLAY 0.978723 (-2950 4175);
PAINT WHITE (-2950 4175);
DISPLAY INVISIBLE (-2950 4175);
FORCEPROP 0 LAST CDS_LOCATION R3498
J 0
(-2950 4175);
DISPLAY 1.021277 (-2950 4175);
DISPLAY INVISIBLE (-2950 4175);
FORCEPROP 0 LAST $SEC 1
J 0
(-2950 4175);
DISPLAY 0.680851 (-2950 4175);
PAINT MONO (-2950 4175);
DISPLAY INVISIBLE (-2950 4175);
FORCEPROP 0 LAST CDS_SEC 1
J 0
(-2950 4175);
DISPLAY 1.021277 (-2950 4175);
DISPLAY INVISIBLE (-2950 4175);
FORCEADD MOSFET_NCH_DUAL..2
(3825 1200);
FORCEPROP 1 LAST PART_NUMBER BAM138K0003
J 0
(3976 1106);
DISPLAY 0.723404 (3976 1106);
PAINT GREEN (3976 1106);
DISPLAY INVISIBLE (3976 1106);
FORCEPROP 1 LAST MATERIAL IC
J 0
(3976 1051);
DISPLAY 0.723404 (3976 1051);
PAINT GREEN (3976 1051);
FORCEPROP 2 LAST VALUE PJT138K
J 0
(4000 1225);
DISPLAY 1.021277 (4000 1225);
FORCEPROP 2 LAST PART_TYPE SMLF
J 0
(4000 1275);
DISPLAY 1.021277 (4000 1275);
FORCEPROP 1 LAST LOCATION Q108
J 0
(3976 1176);
DISPLAY 0.723404 (3976 1176);
PAINT GREEN (3976 1176);
FORCEPROP 0 LASTPIN (3875 1400) $PN 3
R 1
J 0
(3865 1410);
DISPLAY 0.680851 (3865 1410);
PAINT MONO (3865 1410);
FORCEPROP 0 LASTPIN (3625 1150) $PN 5
J 2
(3615 1160);
DISPLAY 0.680851 (3615 1160);
PAINT MONO (3615 1160);
FORCEPROP 0 LASTPIN (3875 1000) $PN 4
R 1
J 2
(3865 990);
DISPLAY 0.680851 (3865 990);
PAINT MONO (3865 990);
FORCEPROP 1 LAST CDS_LMAN_SYM_OUTLINE -150,150,150,-150
J 0
(3825 1200);
DISPLAY 0.468085 (3825 1200);
PAINT GREEN (3825 1200);
DISPLAY INVISIBLE (3825 1200);
FORCEPROP 1 LAST NEEDS_NO_SIZE TRUE
J 0
(3975 1091);
DISPLAY 0.468085 (3975 1091);
PAINT GREEN (3975 1091);
DISPLAY INVISIBLE (3975 1091);
FORCEPROP 2 LAST CDS_LIB pure_quanta
J 0
(3825 1200);
DISPLAY INVISIBLE (3825 1200);
FORCEPROP 1 LAST PATH I168
J 0
(3975 1050);
DISPLAY 0.723404 (3975 1050);
PAINT GREEN (3975 1050);
DISPLAY INVISIBLE (3975 1050);
FORCEPROP 0 LAST $SEC 2
J 0
(4000 1325);
DISPLAY 0.680851 (4000 1325);
PAINT MONO (4000 1325);
DISPLAY INVISIBLE (4000 1325);
FORCEPROP 0 LAST CDS_SEC 2
J 0
(4000 1325);
DISPLAY 1.021277 (4000 1325);
DISPLAY INVISIBLE (4000 1325);
FORCEADD MOSFET_NCH_DUAL..1
(2900 925);
FORCEPROP 1 LAST PART_NUMBER BAM138K0003
J 0
(3051 839);
DISPLAY 0.723404 (3051 839);
PAINT GREEN (3051 839);
DISPLAY INVISIBLE (3051 839);
FORCEPROP 2 LAST PART_TYPE SMLF
J 0
(3075 1000);
DISPLAY 1.021277 (3075 1000);
FORCEPROP 1 LAST MATERIAL IC
J 0
(3051 774);
DISPLAY 0.723404 (3051 774);
PAINT GREEN (3051 774);
FORCEPROP 2 LAST VALUE PJT138K
J 0
(3075 950);
DISPLAY 1.021277 (3075 950);
FORCEPROP 1 LAST $LOCATION Q108
J 0
(3051 899);
DISPLAY 0.723404 (3051 899);
PAINT GREEN (3051 899);
FORCEPROP 0 LASTPIN (2950 1125) $PN 6
R 1
J 0
(2940 1135);
DISPLAY 0.680851 (2940 1135);
PAINT MONO (2940 1135);
FORCEPROP 0 LASTPIN (2700 875) $PN 2
J 2
(2690 885);
DISPLAY 0.680851 (2690 885);
PAINT MONO (2690 885);
FORCEPROP 0 LASTPIN (2950 725) $PN 1
R 1
J 2
(2940 715);
DISPLAY 0.680851 (2940 715);
PAINT MONO (2940 715);
FORCEPROP 1 LAST CDS_LMAN_SYM_OUTLINE -150,150,150,-150
J 0
(2900 925);
DISPLAY 0.468085 (2900 925);
PAINT GREEN (2900 925);
DISPLAY INVISIBLE (2900 925);
FORCEPROP 1 LAST NEEDS_NO_SIZE TRUE
J 0
(2900 924);
DISPLAY 0.468085 (2900 924);
PAINT GREEN (2900 924);
DISPLAY INVISIBLE (2900 924);
FORCEPROP 2 LAST CDS_LIB pure_quanta
J 0
(2900 925);
DISPLAY INVISIBLE (2900 925);
FORCEPROP 1 LAST PATH I169
J 0
(2900 925);
DISPLAY 0.723404 (2900 925);
PAINT GREEN (2900 925);
DISPLAY INVISIBLE (2900 925);
FORCEPROP 0 LAST CDS_LOCATION Q108
J 0
(3075 1050);
DISPLAY 1.021277 (3075 1050);
DISPLAY INVISIBLE (3075 1050);
FORCEPROP 0 LAST $SEC 1
J 0
(3075 1050);
DISPLAY 0.680851 (3075 1050);
PAINT MONO (3075 1050);
DISPLAY INVISIBLE (3075 1050);
FORCEPROP 2 LAST CDS_SEC 1
J 0
(3075 1050);
DISPLAY 1.021277 (3075 1050);
DISPLAY INVISIBLE (3075 1050);
FORCEADD Q_RES..2
(-2975 3525);
FORCEPROP 1 LAST PART_NUMBER CS41002FB09
J 0
(-2935 3400);
DISPLAY 0.510638 (-2935 3400);
DISPLAY INVISIBLE (-2935 3400);
FORCEPROP 1 LAST TOLERANCE 1%
J 0
(-2930 3550);
DISPLAY 0.510638 (-2930 3550);
FORCEPROP 1 LAST VALUE 100K
J 0
(-2930 3600);
DISPLAY 0.510638 (-2930 3600);
FORCEPROP 1 LAST MATERIAL EMPTY
J 0
(-2935 3450);
DISPLAY 0.510638 (-2935 3450);
PAINT RED (-2935 3450);
FORCEPROP 1 LAST WATTAGE 1/16W
J 0
(-2935 3500);
DISPLAY 0.510638 (-2935 3500);
FORCEPROP 1 LAST PACK_TYPE 0402LF
J 0
(-2935 3350);
DISPLAY 0.510638 (-2935 3350);
FORCEPROP 1 LAST $LOCATION R3428
J 0
(-2930 3650);
DISPLAY 0.978723 (-2930 3650);
FORCEPROP 1 LASTPIN (-2975 3625) $PN 1
J 0
(-2970 3587);
DISPLAY 0.787234 (-2970 3587);
PAINT MONO (-2970 3587);
FORCEPROP 1 LASTPIN (-2975 3425) $PN 2
J 0
(-2970 3435);
DISPLAY 0.787234 (-2970 3435);
PAINT MONO (-2970 3435);
FORCEPROP 2 LAST CDS_LIB pure_quanta
J 0
(-2975 3525);
DISPLAY INVISIBLE (-2975 3525);
FORCEPROP 1 LAST PATH I17
J 0
(-2925 3700);
DISPLAY 0.978723 (-2925 3700);
PAINT WHITE (-2925 3700);
DISPLAY INVISIBLE (-2925 3700);
FORCEPROP 0 LAST CDS_LOCATION R3428
J 0
(-2925 3700);
DISPLAY 1.021277 (-2925 3700);
DISPLAY INVISIBLE (-2925 3700);
FORCEPROP 0 LAST $SEC 1
J 0
(-2925 3700);
DISPLAY 0.680851 (-2925 3700);
PAINT MONO (-2925 3700);
DISPLAY INVISIBLE (-2925 3700);
FORCEPROP 0 LAST CDS_SEC 1
J 0
(-2925 3700);
DISPLAY 1.021277 (-2925 3700);
DISPLAY INVISIBLE (-2925 3700);
FORCEADD OFFPAGE..2
(5050 1425);
FORCEPROP 2 LAST $XR0 213 
J 0
(5239 1425);
DISPLAY 0.638298 (5239 1425);
PAINT MONO (5239 1425);
FORCEPROP 2 LAST CDS_LIB standard
J 0
(5050 1425);
DISPLAY INVISIBLE (5050 1425);
FORCEPROP 1 LAST COMMENT_BODY TRUE
J 0
(5005 1330);
DISPLAY 0.872340 (5005 1330);
PAINT GREEN (5005 1330);
DISPLAY INVISIBLE (5005 1330);
FORCEPROP 1 LAST OFFPAGE TRUE
J 0
(5375 1300);
DISPLAY 0.872340 (5375 1300);
PAINT AQUA (5375 1300);
DISPLAY INVISIBLE (5375 1300);
FORCEPROP 2 LAST PATH I170
J 0
(5250 1475);
DISPLAY 1.021277 (5250 1475);
DISPLAY INVISIBLE (5250 1475);
FORCEADD Q_CAP..1
(4775 1025);
FORCEPROP 1 LAST PART_NUMBER TMP_QCH21006JB10
J 0
(4825 875);
DISPLAY 0.638298 (4825 875);
DISPLAY INVISIBLE (4825 875);
FORCEPROP 1 LAST VOLTAGE 50V
J 0
(4825 1025);
DISPLAY 0.638298 (4825 1025);
FORCEPROP 1 LAST PACK_TYPE 0402
J 0
(4825 825);
DISPLAY 0.638298 (4825 825);
FORCEPROP 1 LAST MATERIAL EMPTY
J 0
(4825 925);
DISPLAY 0.638298 (4825 925);
PAINT RED (4825 925);
FORCEPROP 1 LAST TOLERANCE 5%
J 0
(4825 975);
DISPLAY 0.638298 (4825 975);
FORCEPROP 1 LAST VALUE 1000PF
J 0
(4825 1075);
DISPLAY 0.638298 (4825 1075);
FORCEPROP 1 LAST $LOCATION C1988
J 0
(4825 1125);
DISPLAY 0.638298 (4825 1125);
FORCEPROP 1 LASTPIN (4775 1125) $PN 1
J 0
(4785 1105);
DISPLAY 0.787234 (4785 1105);
PAINT MONO (4785 1105);
FORCEPROP 1 LASTPIN (4775 925) $PN 2
J 0
(4785 905);
DISPLAY 0.787234 (4785 905);
PAINT MONO (4785 905);
FORCEPROP 2 LAST CDS_LIB pure_quanta
J 0
(4775 1025);
DISPLAY INVISIBLE (4775 1025);
FORCEPROP 1 LAST PATH I171
J 0
(4825 1175);
DISPLAY 0.978723 (4825 1175);
PAINT WHITE (4825 1175);
DISPLAY INVISIBLE (4825 1175);
FORCEPROP 2 LAST CDS_LOCATION C1988
J 0
(4825 1225);
DISPLAY 1.021277 (4825 1225);
DISPLAY INVISIBLE (4825 1225);
FORCEPROP 2 LAST $SEC 1
J 0
(4825 1225);
DISPLAY 0.680851 (4825 1225);
PAINT MONO (4825 1225);
DISPLAY INVISIBLE (4825 1225);
FORCEPROP 2 LAST CDS_SEC 1
J 0
(4825 1225);
DISPLAY 1.021277 (4825 1225);
DISPLAY INVISIBLE (4825 1225);
FORCEADD UNIVERSAL_GND..1
(4775 825);
FORCEPROP 3 LASTPIN (4775 875) SIG_NAME GND\g
J 0
(4785 885);
DISPLAY 0.659574 (4785 885);
PAINT MONO (4785 885);
DISPLAY INVISIBLE (4785 885);
FORCEPROP 1 LAST HDL_POWER GND
J 1
(4800 750);
DISPLAY 0.872340 (4800 750);
PAINT GREEN (4800 750);
DISPLAY INVISIBLE (4800 750);
FORCEPROP 2 LAST CDS_LIB logical_power
J 0
(4775 825);
DISPLAY INVISIBLE (4775 825);
FORCEPROP 1 LAST PATH I172
J 0
(4850 825);
DISPLAY 0.872340 (4850 825);
PAINT AQUA (4850 825);
DISPLAY INVISIBLE (4850 825);
FORCEADD UNIVERSAL_POWER..1
(3875 1950);
FORCEPROP 3 LASTPIN (3875 1900) SIG_NAME P3V3_AUX\g
J 0
(3885 1910);
DISPLAY 0.659574 (3885 1910);
PAINT MONO (3885 1910);
DISPLAY INVISIBLE (3885 1910);
FORCEPROP 1 LAST HDL_POWER P3V3_AUX
J 1
(3875 2000);
DISPLAY 0.872340 (3875 2000);
PAINT GREEN (3875 2000);
FORCEPROP 2 LAST CDS_LIB logical_power
J 0
(3875 1950);
DISPLAY INVISIBLE (3875 1950);
FORCEPROP 1 LAST PATH I173
J 0
(3925 1975);
DISPLAY 0.872340 (3925 1975);
PAINT AQUA (3925 1975);
DISPLAY INVISIBLE (3925 1975);
FORCEADD Q_RES..2
(3875 1650);
FORCEPROP 1 LAST PART_NUMBER CS24702JB10
J 0
(3915 1475);
DISPLAY 0.638298 (3915 1475);
DISPLAY INVISIBLE (3915 1475);
FORCEPROP 1 LAST VALUE 4.7K
J 0
(3920 1725);
DISPLAY 0.638298 (3920 1725);
FORCEPROP 1 LAST TOLERANCE 5%
J 0
(3920 1675);
DISPLAY 0.638298 (3920 1675);
FORCEPROP 1 LAST PACK_TYPE 0402LF
J 0
(3915 1525);
DISPLAY 0.638298 (3915 1525);
FORCEPROP 1 LAST MATERIAL CHIP
J 0
(3915 1575);
DISPLAY 0.638298 (3915 1575);
FORCEPROP 1 LAST WATTAGE 1/16W
J 0
(3915 1625);
DISPLAY 0.638298 (3915 1625);
FORCEPROP 1 LAST $LOCATION R3504
J 0
(3920 1775);
DISPLAY 0.978723 (3920 1775);
FORCEPROP 1 LASTPIN (3875 1750) $PN 1
J 0
(3880 1712);
DISPLAY 0.787234 (3880 1712);
PAINT MONO (3880 1712);
FORCEPROP 1 LASTPIN (3875 1550) $PN 2
J 0
(3880 1560);
DISPLAY 0.787234 (3880 1560);
PAINT MONO (3880 1560);
FORCEPROP 2 LAST CDS_LIB pure_quanta
J 0
(3875 1650);
DISPLAY INVISIBLE (3875 1650);
FORCEPROP 1 LAST PATH I174
J 0
(3925 1825);
DISPLAY 0.978723 (3925 1825);
PAINT WHITE (3925 1825);
DISPLAY INVISIBLE (3925 1825);
FORCEPROP 0 LAST CDS_LOCATION R3504
J 0
(3925 1825);
DISPLAY 1.021277 (3925 1825);
DISPLAY INVISIBLE (3925 1825);
FORCEPROP 0 LAST $SEC 1
J 0
(3925 1825);
DISPLAY 0.680851 (3925 1825);
PAINT MONO (3925 1825);
DISPLAY INVISIBLE (3925 1825);
FORCEPROP 0 LAST CDS_SEC 1
J 0
(3925 1825);
DISPLAY 1.021277 (3925 1825);
DISPLAY INVISIBLE (3925 1825);
FORCEADD UNIVERSAL_GND..1
(3875 825);
FORCEPROP 3 LASTPIN (3875 875) SIG_NAME GND\g
J 0
(3885 885);
DISPLAY 0.659574 (3885 885);
PAINT MONO (3885 885);
DISPLAY INVISIBLE (3885 885);
FORCEPROP 1 LAST HDL_POWER GND
J 1
(3900 750);
DISPLAY 0.872340 (3900 750);
PAINT GREEN (3900 750);
DISPLAY INVISIBLE (3900 750);
FORCEPROP 2 LAST CDS_LIB logical_power
J 0
(3875 825);
DISPLAY INVISIBLE (3875 825);
FORCEPROP 1 LAST PATH I175
J 0
(3950 825);
DISPLAY 0.872340 (3950 825);
PAINT AQUA (3950 825);
DISPLAY INVISIBLE (3950 825);
FORCEADD UNIVERSAL_POWER..1
(2950 1700);
FORCEPROP 3 LASTPIN (2950 1650) SIG_NAME P3V3_AUX\g
J 0
(2960 1660);
DISPLAY 0.659574 (2960 1660);
PAINT MONO (2960 1660);
DISPLAY INVISIBLE (2960 1660);
FORCEPROP 1 LAST HDL_POWER P3V3_AUX
J 1
(2950 1750);
DISPLAY 0.872340 (2950 1750);
PAINT GREEN (2950 1750);
FORCEPROP 2 LAST CDS_LIB logical_power
J 0
(2950 1700);
PAINT MONO (2950 1700);
DISPLAY INVISIBLE (2950 1700);
FORCEPROP 1 LAST PATH I176
J 0
(3000 1725);
DISPLAY 0.872340 (3000 1725);
PAINT AQUA (3000 1725);
DISPLAY INVISIBLE (3000 1725);
FORCEADD Q_RES..2
(2950 1400);
FORCEPROP 1 LAST PART_NUMBER CS24702JB10
J 0
(2990 1225);
DISPLAY 0.638298 (2990 1225);
DISPLAY INVISIBLE (2990 1225);
FORCEPROP 1 LAST MATERIAL CHIP
J 0
(2990 1325);
DISPLAY 0.638298 (2990 1325);
FORCEPROP 1 LAST TOLERANCE 5%
J 0
(2995 1425);
DISPLAY 0.638298 (2995 1425);
FORCEPROP 1 LAST VALUE 4.7K
J 0
(2995 1475);
DISPLAY 0.638298 (2995 1475);
FORCEPROP 1 LAST WATTAGE 1/16W
J 0
(2990 1375);
DISPLAY 0.638298 (2990 1375);
FORCEPROP 1 LAST PACK_TYPE 0402LF
J 0
(2990 1275);
DISPLAY 0.638298 (2990 1275);
FORCEPROP 1 LAST $LOCATION R3503
J 0
(2995 1525);
DISPLAY 0.638298 (2995 1525);
FORCEPROP 1 LASTPIN (2950 1500) $PN 1
J 0
(2955 1462);
DISPLAY 0.787234 (2955 1462);
FORCEPROP 1 LASTPIN (2950 1300) $PN 2
J 0
(2955 1310);
DISPLAY 0.787234 (2955 1310);
FORCEPROP 2 LAST CDS_LIB pure_quanta
J 0
(2950 1400);
PAINT MONO (2950 1400);
DISPLAY INVISIBLE (2950 1400);
FORCEPROP 1 LAST PATH I177
J 0
(3000 1575);
DISPLAY 0.978723 (3000 1575);
PAINT WHITE (3000 1575);
DISPLAY INVISIBLE (3000 1575);
FORCEPROP 2 LAST CDS_LOCATION R3503
J 0
(3000 1625);
DISPLAY 1.021277 (3000 1625);
DISPLAY INVISIBLE (3000 1625);
FORCEPROP 2 LAST $SEC 1
J 0
(3000 1625);
DISPLAY 0.680851 (3000 1625);
PAINT MONO (3000 1625);
DISPLAY INVISIBLE (3000 1625);
FORCEPROP 2 LAST CDS_SEC 1
J 0
(3000 1625);
DISPLAY 1.021277 (3000 1625);
DISPLAY INVISIBLE (3000 1625);
FORCEADD UNIVERSAL_GND..1
(2950 550);
FORCEPROP 3 LASTPIN (2950 600) SIG_NAME GND\g
J 0
(2960 610);
DISPLAY 0.659574 (2960 610);
PAINT MONO (2960 610);
DISPLAY INVISIBLE (2960 610);
FORCEPROP 2 LAST CDS_LIB logical_power
J 0
(2950 550);
DISPLAY INVISIBLE (2950 550);
FORCEPROP 1 LAST HDL_POWER GND
J 1
(2975 475);
DISPLAY 0.872340 (2975 475);
PAINT GREEN (2975 475);
DISPLAY INVISIBLE (2975 475);
FORCEPROP 1 LAST PATH I178
J 0
(3025 550);
DISPLAY 0.872340 (3025 550);
PAINT AQUA (3025 550);
DISPLAY INVISIBLE (3025 550);
FORCEADD UNIVERSAL_POWER..1
(1700 1400);
FORCEPROP 3 LASTPIN (1700 1350) SIG_NAME P3V3_AUX\g
J 0
(1710 1360);
DISPLAY 0.659574 (1710 1360);
PAINT MONO (1710 1360);
DISPLAY INVISIBLE (1710 1360);
FORCEPROP 1 LAST HDL_POWER P3V3_AUX
J 1
(1700 1450);
DISPLAY 0.872340 (1700 1450);
PAINT GREEN (1700 1450);
FORCEPROP 2 LAST CDS_LIB logical_power
J 0
(1700 1400);
PAINT MONO (1700 1400);
DISPLAY INVISIBLE (1700 1400);
FORCEPROP 1 LAST PATH I179
J 0
(1750 1425);
DISPLAY 0.872340 (1750 1425);
PAINT AQUA (1750 1425);
DISPLAY INVISIBLE (1750 1425);
FORCEADD OFFPAGE..4
R 2
(-3250 3725);
FORCEPROP 2 LAST $XR0 143 
J 0
(-3532 3725);
DISPLAY 0.638298 (-3532 3725);
PAINT MONO (-3532 3725);
FORCEPROP 2 LAST PATH I18
J 0
(-3525 3775);
DISPLAY 1.021277 (-3525 3775);
DISPLAY INVISIBLE (-3525 3775);
FORCEPROP 1 LAST OFFPAGE TRUE
J 2
(-3575 3600);
DISPLAY 0.872340 (-3575 3600);
PAINT GREEN (-3575 3600);
DISPLAY INVISIBLE (-3575 3600);
FORCEPROP 1 LAST COMMENT_BODY TRUE
J 2
(-3225 3625);
DISPLAY 0.872340 (-3225 3625);
PAINT GREEN (-3225 3625);
DISPLAY INVISIBLE (-3225 3625);
FORCEPROP 2 LAST CDS_LIB standard
J 0
(-3250 3725);
DISPLAY INVISIBLE (-3250 3725);
FORCEADD Q_RES..2
(1725 675);
FORCEPROP 1 LAST PART_NUMBER CS41002FB09
J 0
(1765 550);
DISPLAY 0.510638 (1765 550);
DISPLAY INVISIBLE (1765 550);
FORCEPROP 1 LAST PACK_TYPE 0402LF
J 0
(1765 500);
DISPLAY 0.510638 (1765 500);
FORCEPROP 1 LAST VALUE 100K
J 0
(1770 750);
DISPLAY 0.510638 (1770 750);
FORCEPROP 1 LAST TOLERANCE 1%
J 0
(1770 700);
DISPLAY 0.510638 (1770 700);
FORCEPROP 1 LAST MATERIAL EMPTY
J 0
(1765 600);
DISPLAY 0.510638 (1765 600);
PAINT RED (1765 600);
FORCEPROP 1 LAST WATTAGE 1/16W
J 0
(1765 650);
DISPLAY 0.510638 (1765 650);
FORCEPROP 1 LAST $LOCATION R3502
J 0
(1770 800);
DISPLAY 0.978723 (1770 800);
FORCEPROP 1 LASTPIN (1725 775) $PN 1
J 0
(1730 737);
DISPLAY 0.787234 (1730 737);
PAINT MONO (1730 737);
FORCEPROP 1 LASTPIN (1725 575) $PN 2
J 0
(1730 585);
DISPLAY 0.787234 (1730 585);
PAINT MONO (1730 585);
FORCEPROP 1 LAST PATH I181
J 0
(1775 850);
DISPLAY 0.978723 (1775 850);
PAINT WHITE (1775 850);
DISPLAY INVISIBLE (1775 850);
FORCEPROP 2 LAST CDS_LIB pure_quanta
J 0
(1725 675);
DISPLAY INVISIBLE (1725 675);
FORCEPROP 0 LAST CDS_LOCATION R3502
J 0
(1775 850);
DISPLAY 1.021277 (1775 850);
DISPLAY INVISIBLE (1775 850);
FORCEPROP 0 LAST $SEC 1
J 0
(1775 850);
DISPLAY 0.680851 (1775 850);
PAINT MONO (1775 850);
DISPLAY INVISIBLE (1775 850);
FORCEPROP 0 LAST CDS_SEC 1
J 0
(1775 850);
DISPLAY 1.021277 (1775 850);
DISPLAY INVISIBLE (1775 850);
FORCEADD UNIVERSAL_GND..1
(1725 475);
FORCEPROP 3 LASTPIN (1725 525) SIG_NAME GND\g
J 0
(1735 535);
DISPLAY 0.659574 (1735 535);
PAINT MONO (1735 535);
DISPLAY INVISIBLE (1735 535);
FORCEPROP 1 LAST PATH I182
J 0
(1800 475);
DISPLAY 0.872340 (1800 475);
PAINT AQUA (1800 475);
DISPLAY INVISIBLE (1800 475);
FORCEPROP 1 LAST HDL_POWER GND
J 1
(1750 400);
DISPLAY 0.872340 (1750 400);
PAINT GREEN (1750 400);
DISPLAY INVISIBLE (1750 400);
FORCEPROP 2 LAST CDS_LIB logical_power
J 0
(1725 475);
DISPLAY INVISIBLE (1725 475);
FORCEADD OFFPAGE..4
R 2
(1425 875);
FORCEPROP 2 LAST $XR0 140 
J 0
(1173 875);
DISPLAY 0.638298 (1173 875);
PAINT MONO (1173 875);
FORCEPROP 2 LAST CDS_LIB standard
J 0
(1425 875);
DISPLAY INVISIBLE (1425 875);
FORCEPROP 1 LAST COMMENT_BODY TRUE
J 2
(1450 775);
DISPLAY 0.872340 (1450 775);
PAINT GREEN (1450 775);
DISPLAY INVISIBLE (1450 775);
FORCEPROP 1 LAST OFFPAGE TRUE
J 2
(1100 750);
DISPLAY 0.872340 (1100 750);
PAINT GREEN (1100 750);
DISPLAY INVISIBLE (1100 750);
FORCEPROP 2 LAST PATH I183
J 0
(1175 925);
DISPLAY 1.021277 (1175 925);
DISPLAY INVISIBLE (1175 925);
FORCEADD Q_RES..2
(1700 1100);
FORCEPROP 1 LAST PART_NUMBER CS35492FB03
J 0
(1740 975);
DISPLAY 0.787234 (1740 975);
DISPLAY INVISIBLE (1740 975);
FORCEPROP 1 LAST WATTAGE 1/16W
J 0
(1740 1075);
DISPLAY 0.787234 (1740 1075);
FORCEPROP 1 LAST MATERIAL CHIP
J 0
(1740 1025);
DISPLAY 0.787234 (1740 1025);
FORCEPROP 1 LAST TOLERANCE 1%
J 0
(1745 1125);
DISPLAY 0.787234 (1745 1125);
FORCEPROP 1 LAST VALUE 54.9K
J 0
(1745 1175);
DISPLAY 0.787234 (1745 1175);
FORCEPROP 1 LAST PACK_TYPE 0402LF
J 0
(1740 925);
DISPLAY 0.787234 (1740 925);
FORCEPROP 1 LAST $LOCATION R3525
J 0
(1745 1225);
DISPLAY 0.978723 (1745 1225);
FORCEPROP 1 LASTPIN (1700 1200) $PN 1
J 0
(1705 1162);
DISPLAY 0.787234 (1705 1162);
PAINT MONO (1705 1162);
FORCEPROP 1 LASTPIN (1700 1000) $PN 2
J 0
(1705 1010);
DISPLAY 0.787234 (1705 1010);
PAINT MONO (1705 1010);
FORCEPROP 1 LAST PATH I184
J 0
(1750 1275);
DISPLAY 0.978723 (1750 1275);
PAINT WHITE (1750 1275);
DISPLAY INVISIBLE (1750 1275);
FORCEPROP 2 LAST CDS_LIB pure_quanta
J 0
(1700 1100);
DISPLAY INVISIBLE (1700 1100);
FORCEPROP 0 LAST CDS_LOCATION R3525
J 0
(1750 1275);
DISPLAY 1.021277 (1750 1275);
DISPLAY INVISIBLE (1750 1275);
FORCEPROP 0 LAST $SEC 1
J 0
(1750 1275);
DISPLAY 0.680851 (1750 1275);
PAINT MONO (1750 1275);
DISPLAY INVISIBLE (1750 1275);
FORCEPROP 0 LAST CDS_SEC 1
J 0
(1750 1275);
DISPLAY 1.021277 (1750 1275);
DISPLAY INVISIBLE (1750 1275);
FORCEADD OFFPAGE..2
(3500 3050);
FORCEPROP 2 LAST $XR0 246 
J 0
(3689 3050);
DISPLAY 0.638298 (3689 3050);
PAINT MONO (3689 3050);
FORCEPROP 1 LAST OFFPAGE TRUE
J 0
(3825 2925);
DISPLAY 0.872340 (3825 2925);
PAINT AQUA (3825 2925);
DISPLAY INVISIBLE (3825 2925);
FORCEPROP 1 LAST COMMENT_BODY TRUE
J 0
(3455 2955);
DISPLAY 0.872340 (3455 2955);
PAINT GREEN (3455 2955);
DISPLAY INVISIBLE (3455 2955);
FORCEPROP 2 LAST PATH I185
J 0
(3675 3125);
DISPLAY 1.021277 (3675 3125);
DISPLAY INVISIBLE (3675 3125);
FORCEPROP 2 LAST CDS_LIB standard
J 0
(3500 3050);
DISPLAY INVISIBLE (3500 3050);
FORCEADD UNIVERSAL_GND..1
(-2950 -1000);
FORCEPROP 3 LASTPIN (-2950 -950) SIG_NAME GND\g
J 0
(-2940 -940);
DISPLAY 0.659574 (-2940 -940);
PAINT MONO (-2940 -940);
DISPLAY INVISIBLE (-2940 -940);
FORCEPROP 2 LAST CDS_LIB logical_power
J 0
(-2950 -1000);
DISPLAY INVISIBLE (-2950 -1000);
FORCEPROP 1 LAST HDL_POWER GND
J 1
(-2925 -1075);
DISPLAY 0.872340 (-2925 -1075);
PAINT GREEN (-2925 -1075);
DISPLAY INVISIBLE (-2925 -1075);
FORCEPROP 1 LAST PATH I2
J 0
(-2875 -1000);
DISPLAY 0.872340 (-2875 -1000);
PAINT AQUA (-2875 -1000);
DISPLAY INVISIBLE (-2875 -1000);
FORCEADD UNIVERSAL_POWER..1
(-3000 4250);
FORCEPROP 3 LASTPIN (-3000 4200) SIG_NAME P3V3_AUX\g
J 0
(-2990 4210);
DISPLAY 0.659574 (-2990 4210);
PAINT MONO (-2990 4210);
DISPLAY INVISIBLE (-2990 4210);
FORCEPROP 1 LAST HDL_POWER P3V3_AUX
J 1
(-3000 4300);
DISPLAY 0.872340 (-3000 4300);
PAINT GREEN (-3000 4300);
FORCEPROP 1 LAST PATH I20
J 0
(-2950 4275);
DISPLAY 0.872340 (-2950 4275);
PAINT AQUA (-2950 4275);
DISPLAY INVISIBLE (-2950 4275);
FORCEPROP 2 LAST CDS_LIB logical_power
J 0
(-3000 4250);
PAINT MONO (-3000 4250);
DISPLAY INVISIBLE (-3000 4250);
FORCEADD MOSFET_NCH_DUAL..1
(-1775 -550);
FORCEPROP 1 LAST PART_NUMBER BAM138K0003
J 0
(-1624 -636);
DISPLAY 0.723404 (-1624 -636);
PAINT GREEN (-1624 -636);
DISPLAY INVISIBLE (-1624 -636);
FORCEPROP 2 LAST VALUE PJT138K
J 0
(-1600 -525);
DISPLAY 1.021277 (-1600 -525);
FORCEPROP 1 LAST MATERIAL IC
J 0
(-1624 -701);
DISPLAY 0.723404 (-1624 -701);
PAINT GREEN (-1624 -701);
FORCEPROP 2 LAST PART_TYPE SMLF
J 0
(-1600 -475);
DISPLAY 1.021277 (-1600 -475);
FORCEPROP 1 LAST $LOCATION Q104
J 0
(-1624 -576);
DISPLAY 0.723404 (-1624 -576);
PAINT GREEN (-1624 -576);
FORCEPROP 0 LASTPIN (-1725 -350) $PN 6
R 1
J 0
(-1735 -340);
DISPLAY 0.680851 (-1735 -340);
PAINT MONO (-1735 -340);
FORCEPROP 0 LASTPIN (-1975 -600) $PN 2
J 2
(-1985 -590);
DISPLAY 0.680851 (-1985 -590);
PAINT MONO (-1985 -590);
FORCEPROP 0 LASTPIN (-1725 -750) $PN 1
R 1
J 2
(-1735 -760);
DISPLAY 0.680851 (-1735 -760);
PAINT MONO (-1735 -760);
FORCEPROP 1 LAST PATH I21
J 0
(-1775 -550);
DISPLAY 0.723404 (-1775 -550);
PAINT GREEN (-1775 -550);
DISPLAY INVISIBLE (-1775 -550);
FORCEPROP 2 LAST CDS_LIB pure_quanta
J 0
(-1775 -550);
DISPLAY INVISIBLE (-1775 -550);
FORCEPROP 1 LAST NEEDS_NO_SIZE TRUE
J 0
(-1775 -551);
DISPLAY 0.468085 (-1775 -551);
PAINT GREEN (-1775 -551);
DISPLAY INVISIBLE (-1775 -551);
FORCEPROP 1 LAST CDS_LMAN_SYM_OUTLINE -150,150,150,-150
J 0
(-1775 -550);
DISPLAY 0.468085 (-1775 -550);
PAINT GREEN (-1775 -550);
DISPLAY INVISIBLE (-1775 -550);
FORCEPROP 0 LAST CDS_LOCATION Q104
J 0
(-1600 -425);
DISPLAY 1.021277 (-1600 -425);
DISPLAY INVISIBLE (-1600 -425);
FORCEPROP 0 LAST $SEC 1
J 0
(-1600 -425);
DISPLAY 0.680851 (-1600 -425);
PAINT MONO (-1600 -425);
DISPLAY INVISIBLE (-1600 -425);
FORCEPROP 2 LAST CDS_SEC 1
J 0
(-1600 -425);
DISPLAY 1.021277 (-1600 -425);
DISPLAY INVISIBLE (-1600 -425);
FORCEADD UNIVERSAL_GND..1
(-1725 -925);
FORCEPROP 3 LASTPIN (-1725 -875) SIG_NAME GND\g
J 0
(-1715 -865);
DISPLAY 0.659574 (-1715 -865);
PAINT MONO (-1715 -865);
DISPLAY INVISIBLE (-1715 -865);
FORCEPROP 1 LAST PATH I22
J 0
(-1650 -925);
DISPLAY 0.872340 (-1650 -925);
PAINT AQUA (-1650 -925);
DISPLAY INVISIBLE (-1650 -925);
FORCEPROP 1 LAST HDL_POWER GND
J 1
(-1700 -1000);
DISPLAY 0.872340 (-1700 -1000);
PAINT GREEN (-1700 -1000);
DISPLAY INVISIBLE (-1700 -1000);
FORCEPROP 2 LAST CDS_LIB logical_power
J 0
(-1725 -925);
DISPLAY INVISIBLE (-1725 -925);
FORCEADD Q_RES..2
(-1725 -75);
FORCEPROP 1 LAST PART_NUMBER CS24702JB10
J 0
(-1685 -250);
DISPLAY 0.638298 (-1685 -250);
DISPLAY INVISIBLE (-1685 -250);
FORCEPROP 1 LAST WATTAGE 1/16W
J 0
(-1685 -100);
DISPLAY 0.638298 (-1685 -100);
FORCEPROP 1 LAST MATERIAL CHIP
J 0
(-1685 -150);
DISPLAY 0.638298 (-1685 -150);
FORCEPROP 1 LAST VALUE 4.7K
J 0
(-1680 0);
DISPLAY 0.638298 (-1680 0);
FORCEPROP 1 LAST TOLERANCE 5%
J 0
(-1680 -50);
DISPLAY 0.638298 (-1680 -50);
FORCEPROP 1 LAST PACK_TYPE 0402LF
J 0
(-1685 -200);
DISPLAY 0.638298 (-1685 -200);
FORCEPROP 1 LAST $LOCATION R3435
J 0
(-1680 50);
DISPLAY 0.638298 (-1680 50);
FORCEPROP 1 LASTPIN (-1725 25) $PN 1
J 0
(-1720 -13);
DISPLAY 0.787234 (-1720 -13);
FORCEPROP 1 LASTPIN (-1725 -175) $PN 2
J 0
(-1720 -165);
DISPLAY 0.787234 (-1720 -165);
FORCEPROP 1 LAST PATH I23
J 0
(-1675 100);
DISPLAY 0.978723 (-1675 100);
PAINT WHITE (-1675 100);
DISPLAY INVISIBLE (-1675 100);
FORCEPROP 2 LAST CDS_LIB pure_quanta
J 0
(-1725 -75);
PAINT MONO (-1725 -75);
DISPLAY INVISIBLE (-1725 -75);
FORCEPROP 2 LAST CDS_LOCATION R3435
J 0
(-1675 150);
DISPLAY 1.021277 (-1675 150);
DISPLAY INVISIBLE (-1675 150);
FORCEPROP 2 LAST $SEC 1
J 0
(-1675 150);
DISPLAY 0.680851 (-1675 150);
PAINT MONO (-1675 150);
DISPLAY INVISIBLE (-1675 150);
FORCEPROP 2 LAST CDS_SEC 1
J 0
(-1675 150);
DISPLAY 1.021277 (-1675 150);
DISPLAY INVISIBLE (-1675 150);
FORCEADD UNIVERSAL_POWER..1
(-1725 225);
FORCEPROP 3 LASTPIN (-1725 175) SIG_NAME P3V3_AUX\g
J 0
(-1715 185);
DISPLAY 0.659574 (-1715 185);
PAINT MONO (-1715 185);
DISPLAY INVISIBLE (-1715 185);
FORCEPROP 1 LAST HDL_POWER P3V3_AUX
J 1
(-1725 275);
DISPLAY 0.872340 (-1725 275);
PAINT GREEN (-1725 275);
FORCEPROP 1 LAST PATH I24
J 0
(-1675 250);
DISPLAY 0.872340 (-1675 250);
PAINT AQUA (-1675 250);
DISPLAY INVISIBLE (-1675 250);
FORCEPROP 2 LAST CDS_LIB logical_power
J 0
(-1725 225);
PAINT MONO (-1725 225);
DISPLAY INVISIBLE (-1725 225);
FORCEADD UNIVERSAL_GND..1
(-800 -650);
FORCEPROP 3 LASTPIN (-800 -600) SIG_NAME GND\g
J 0
(-790 -590);
DISPLAY 0.659574 (-790 -590);
PAINT MONO (-790 -590);
DISPLAY INVISIBLE (-790 -590);
FORCEPROP 1 LAST PATH I25
J 0
(-725 -650);
DISPLAY 0.872340 (-725 -650);
PAINT AQUA (-725 -650);
DISPLAY INVISIBLE (-725 -650);
FORCEPROP 2 LAST CDS_LIB logical_power
J 0
(-800 -650);
DISPLAY INVISIBLE (-800 -650);
FORCEPROP 1 LAST HDL_POWER GND
J 1
(-775 -725);
DISPLAY 0.872340 (-775 -725);
PAINT GREEN (-775 -725);
DISPLAY INVISIBLE (-775 -725);
FORCEADD MOSFET_NCH_DUAL..2
(-850 -275);
FORCEPROP 1 LAST PART_NUMBER BAM138K0003
J 0
(-699 -369);
DISPLAY 0.723404 (-699 -369);
PAINT GREEN (-699 -369);
DISPLAY INVISIBLE (-699 -369);
FORCEPROP 1 LAST MATERIAL IC
J 0
(-699 -424);
DISPLAY 0.723404 (-699 -424);
PAINT GREEN (-699 -424);
FORCEPROP 2 LAST PART_TYPE SMLF
J 0
(-675 -200);
DISPLAY 1.021277 (-675 -200);
FORCEPROP 2 LAST VALUE PJT138K
J 0
(-675 -250);
DISPLAY 1.021277 (-675 -250);
FORCEPROP 1 LAST LOCATION Q104
J 0
(-699 -299);
DISPLAY 0.723404 (-699 -299);
PAINT GREEN (-699 -299);
FORCEPROP 0 LASTPIN (-800 -75) $PN 3
R 1
J 0
(-810 -65);
DISPLAY 0.680851 (-810 -65);
PAINT MONO (-810 -65);
FORCEPROP 0 LASTPIN (-1050 -325) $PN 5
J 2
(-1060 -315);
DISPLAY 0.680851 (-1060 -315);
PAINT MONO (-1060 -315);
FORCEPROP 0 LASTPIN (-800 -475) $PN 4
R 1
J 2
(-810 -485);
DISPLAY 0.680851 (-810 -485);
PAINT MONO (-810 -485);
FORCEPROP 1 LAST PATH I26
J 0
(-700 -425);
DISPLAY 0.723404 (-700 -425);
PAINT GREEN (-700 -425);
DISPLAY INVISIBLE (-700 -425);
FORCEPROP 2 LAST CDS_LIB pure_quanta
J 0
(-850 -275);
DISPLAY INVISIBLE (-850 -275);
FORCEPROP 1 LAST NEEDS_NO_SIZE TRUE
J 0
(-700 -384);
DISPLAY 0.468085 (-700 -384);
PAINT GREEN (-700 -384);
DISPLAY INVISIBLE (-700 -384);
FORCEPROP 1 LAST CDS_LMAN_SYM_OUTLINE -150,150,150,-150
J 0
(-850 -275);
DISPLAY 0.468085 (-850 -275);
PAINT GREEN (-850 -275);
DISPLAY INVISIBLE (-850 -275);
FORCEPROP 0 LAST $SEC 2
J 0
(-675 -150);
DISPLAY 0.680851 (-675 -150);
PAINT MONO (-675 -150);
DISPLAY INVISIBLE (-675 -150);
FORCEPROP 0 LAST CDS_SEC 2
J 0
(-675 -150);
DISPLAY 1.021277 (-675 -150);
DISPLAY INVISIBLE (-675 -150);
FORCEADD Q_RES..2
(-800 175);
FORCEPROP 1 LAST PART_NUMBER CS24702JB10
J 0
(-760 0);
DISPLAY 0.638298 (-760 0);
DISPLAY INVISIBLE (-760 0);
FORCEPROP 1 LAST TOLERANCE 5%
J 0
(-755 200);
DISPLAY 0.638298 (-755 200);
FORCEPROP 1 LAST MATERIAL CHIP
J 0
(-760 100);
DISPLAY 0.638298 (-760 100);
FORCEPROP 1 LAST WATTAGE 1/16W
J 0
(-760 150);
DISPLAY 0.638298 (-760 150);
FORCEPROP 1 LAST PACK_TYPE 0402LF
J 0
(-760 50);
DISPLAY 0.638298 (-760 50);
FORCEPROP 1 LAST VALUE 4.7K
J 0
(-755 250);
DISPLAY 0.638298 (-755 250);
FORCEPROP 1 LAST $LOCATION R3437
J 0
(-755 300);
DISPLAY 0.978723 (-755 300);
FORCEPROP 1 LASTPIN (-800 275) $PN 1
J 0
(-795 237);
DISPLAY 0.787234 (-795 237);
PAINT MONO (-795 237);
FORCEPROP 1 LASTPIN (-800 75) $PN 2
J 0
(-795 85);
DISPLAY 0.787234 (-795 85);
PAINT MONO (-795 85);
FORCEPROP 1 LAST PATH I27
J 0
(-750 350);
DISPLAY 0.978723 (-750 350);
PAINT WHITE (-750 350);
DISPLAY INVISIBLE (-750 350);
FORCEPROP 2 LAST CDS_LIB pure_quanta
J 0
(-800 175);
DISPLAY INVISIBLE (-800 175);
FORCEPROP 0 LAST CDS_LOCATION R3437
J 0
(-750 350);
DISPLAY 1.021277 (-750 350);
DISPLAY INVISIBLE (-750 350);
FORCEPROP 0 LAST $SEC 1
J 0
(-750 350);
DISPLAY 0.680851 (-750 350);
PAINT MONO (-750 350);
DISPLAY INVISIBLE (-750 350);
FORCEPROP 0 LAST CDS_SEC 1
J 0
(-750 350);
DISPLAY 1.021277 (-750 350);
DISPLAY INVISIBLE (-750 350);
FORCEADD UNIVERSAL_POWER..1
(-800 475);
FORCEPROP 3 LASTPIN (-800 425) SIG_NAME P3V3_AUX\g
J 0
(-790 435);
DISPLAY 0.659574 (-790 435);
PAINT MONO (-790 435);
DISPLAY INVISIBLE (-790 435);
FORCEPROP 1 LAST HDL_POWER P3V3_AUX
J 1
(-800 525);
DISPLAY 0.872340 (-800 525);
PAINT GREEN (-800 525);
FORCEPROP 1 LAST PATH I28
J 0
(-750 500);
DISPLAY 0.872340 (-750 500);
PAINT AQUA (-750 500);
DISPLAY INVISIBLE (-750 500);
FORCEPROP 2 LAST CDS_LIB logical_power
J 0
(-800 475);
DISPLAY INVISIBLE (-800 475);
FORCEADD UNIVERSAL_GND..1
(100 -650);
FORCEPROP 3 LASTPIN (100 -600) SIG_NAME GND\g
J 0
(110 -590);
DISPLAY 0.659574 (110 -590);
PAINT MONO (110 -590);
DISPLAY INVISIBLE (110 -590);
FORCEPROP 1 LAST PATH I29
J 0
(175 -650);
DISPLAY 0.872340 (175 -650);
PAINT AQUA (175 -650);
DISPLAY INVISIBLE (175 -650);
FORCEPROP 2 LAST CDS_LIB logical_power
J 0
(100 -650);
DISPLAY INVISIBLE (100 -650);
FORCEPROP 1 LAST HDL_POWER GND
J 1
(125 -725);
DISPLAY 0.872340 (125 -725);
PAINT GREEN (125 -725);
DISPLAY INVISIBLE (125 -725);
FORCEADD Q_RES..2
(-2950 -800);
FORCEPROP 1 LAST PART_NUMBER CS41002FB09
J 0
(-2910 -925);
DISPLAY 0.510638 (-2910 -925);
DISPLAY INVISIBLE (-2910 -925);
FORCEPROP 1 LAST MATERIAL EMPTY
J 0
(-2910 -875);
DISPLAY 0.510638 (-2910 -875);
FORCEPROP 1 LAST WATTAGE 1/16W
J 0
(-2910 -825);
DISPLAY 0.510638 (-2910 -825);
FORCEPROP 1 LAST TOLERANCE 1%
J 0
(-2905 -775);
DISPLAY 0.510638 (-2905 -775);
FORCEPROP 1 LAST VALUE 100K
J 0
(-2905 -725);
DISPLAY 0.510638 (-2905 -725);
FORCEPROP 1 LAST PACK_TYPE 0402LF
J 0
(-2910 -975);
DISPLAY 0.510638 (-2910 -975);
FORCEPROP 1 LAST $LOCATION R3430
J 0
(-2905 -675);
DISPLAY 0.978723 (-2905 -675);
FORCEPROP 1 LASTPIN (-2950 -700) $PN 1
J 0
(-2945 -738);
DISPLAY 0.787234 (-2945 -738);
PAINT MONO (-2945 -738);
FORCEPROP 1 LASTPIN (-2950 -900) $PN 2
J 0
(-2945 -890);
DISPLAY 0.787234 (-2945 -890);
PAINT MONO (-2945 -890);
FORCEPROP 2 LAST CDS_LIB pure_quanta
J 0
(-2950 -800);
DISPLAY INVISIBLE (-2950 -800);
FORCEPROP 1 LAST PATH I3
J 0
(-2900 -625);
DISPLAY 0.978723 (-2900 -625);
PAINT WHITE (-2900 -625);
DISPLAY INVISIBLE (-2900 -625);
FORCEPROP 0 LAST CDS_LOCATION R3430
J 0
(-2900 -625);
DISPLAY 1.021277 (-2900 -625);
DISPLAY INVISIBLE (-2900 -625);
FORCEPROP 0 LAST $SEC 1
J 0
(-2900 -625);
DISPLAY 0.680851 (-2900 -625);
PAINT MONO (-2900 -625);
DISPLAY INVISIBLE (-2900 -625);
FORCEPROP 0 LAST CDS_SEC 1
J 0
(-2900 -625);
DISPLAY 1.021277 (-2900 -625);
DISPLAY INVISIBLE (-2900 -625);
FORCEADD Q_CAP..1
(100 -450);
FORCEPROP 1 LAST PART_NUMBER TMP_QCH21006JB10
J 0
(150 -600);
DISPLAY 0.638298 (150 -600);
DISPLAY INVISIBLE (150 -600);
FORCEPROP 1 LAST MATERIAL EMPTY
J 0
(150 -550);
DISPLAY 0.638298 (150 -550);
PAINT RED (150 -550);
FORCEPROP 1 LAST PACK_TYPE 0402
J 0
(150 -650);
DISPLAY 0.638298 (150 -650);
FORCEPROP 1 LAST VALUE 1000PF
J 0
(150 -400);
DISPLAY 0.638298 (150 -400);
FORCEPROP 1 LAST VOLTAGE 50V
J 0
(150 -450);
DISPLAY 0.638298 (150 -450);
FORCEPROP 1 LAST TOLERANCE 5%
J 0
(150 -500);
DISPLAY 0.638298 (150 -500);
FORCEPROP 1 LAST $LOCATION C1976
J 0
(150 -350);
DISPLAY 0.638298 (150 -350);
FORCEPROP 1 LASTPIN (100 -350) $PN 1
J 0
(110 -370);
DISPLAY 0.787234 (110 -370);
PAINT MONO (110 -370);
FORCEPROP 1 LASTPIN (100 -550) $PN 2
J 0
(110 -570);
DISPLAY 0.787234 (110 -570);
PAINT MONO (110 -570);
FORCEPROP 1 LAST PATH I30
J 0
(150 -300);
DISPLAY 0.978723 (150 -300);
PAINT WHITE (150 -300);
DISPLAY INVISIBLE (150 -300);
FORCEPROP 2 LAST CDS_LIB pure_quanta
J 0
(100 -450);
DISPLAY INVISIBLE (100 -450);
FORCEPROP 2 LAST CDS_LOCATION C1976
J 0
(150 -250);
DISPLAY 1.021277 (150 -250);
DISPLAY INVISIBLE (150 -250);
FORCEPROP 2 LAST $SEC 1
J 0
(150 -250);
DISPLAY 0.680851 (150 -250);
PAINT MONO (150 -250);
DISPLAY INVISIBLE (150 -250);
FORCEPROP 2 LAST CDS_SEC 1
J 0
(150 -250);
DISPLAY 1.021277 (150 -250);
DISPLAY INVISIBLE (150 -250);
FORCEADD OFFPAGE..2
(375 -50);
FORCEPROP 2 LAST $XR0 213 
J 0
(564 -50);
DISPLAY 0.638298 (564 -50);
PAINT MONO (564 -50);
FORCEPROP 2 LAST PATH I31
J 0
(575 0);
DISPLAY 1.021277 (575 0);
DISPLAY INVISIBLE (575 0);
FORCEPROP 1 LAST OFFPAGE TRUE
J 0
(700 -175);
DISPLAY 0.872340 (700 -175);
PAINT AQUA (700 -175);
DISPLAY INVISIBLE (700 -175);
FORCEPROP 1 LAST COMMENT_BODY TRUE
J 0
(330 -145);
DISPLAY 0.872340 (330 -145);
PAINT GREEN (330 -145);
DISPLAY INVISIBLE (330 -145);
FORCEPROP 2 LAST CDS_LIB standard
J 0
(375 -50);
DISPLAY INVISIBLE (375 -50);
FORCEADD MOSFET_NCH_DUAL..1
(-1800 1025);
FORCEPROP 1 LAST PART_NUMBER BAM138K0003
J 0
(-1649 939);
DISPLAY 0.723404 (-1649 939);
PAINT GREEN (-1649 939);
DISPLAY INVISIBLE (-1649 939);
FORCEPROP 2 LAST PART_TYPE SMLF
J 0
(-1625 1100);
DISPLAY 1.021277 (-1625 1100);
FORCEPROP 2 LAST VALUE PJT138K
J 0
(-1625 1050);
DISPLAY 1.021277 (-1625 1050);
FORCEPROP 1 LAST MATERIAL IC
J 0
(-1649 874);
DISPLAY 0.723404 (-1649 874);
PAINT GREEN (-1649 874);
FORCEPROP 1 LAST $LOCATION Q103
J 0
(-1649 999);
DISPLAY 0.723404 (-1649 999);
PAINT GREEN (-1649 999);
FORCEPROP 0 LASTPIN (-1750 1225) $PN 6
R 1
J 0
(-1760 1235);
DISPLAY 0.680851 (-1760 1235);
PAINT MONO (-1760 1235);
FORCEPROP 0 LASTPIN (-2000 975) $PN 2
J 2
(-2010 985);
DISPLAY 0.680851 (-2010 985);
PAINT MONO (-2010 985);
FORCEPROP 0 LASTPIN (-1750 825) $PN 1
R 1
J 2
(-1760 815);
DISPLAY 0.680851 (-1760 815);
PAINT MONO (-1760 815);
FORCEPROP 2 LAST CDS_LIB pure_quanta
J 0
(-1800 1025);
DISPLAY INVISIBLE (-1800 1025);
FORCEPROP 1 LAST NEEDS_NO_SIZE TRUE
J 0
(-1800 1024);
DISPLAY 0.468085 (-1800 1024);
PAINT GREEN (-1800 1024);
DISPLAY INVISIBLE (-1800 1024);
FORCEPROP 1 LAST CDS_LMAN_SYM_OUTLINE -150,150,150,-150
J 0
(-1800 1025);
DISPLAY 0.468085 (-1800 1025);
PAINT GREEN (-1800 1025);
DISPLAY INVISIBLE (-1800 1025);
FORCEPROP 1 LAST PATH I37
J 0
(-1800 1025);
DISPLAY 0.723404 (-1800 1025);
PAINT GREEN (-1800 1025);
DISPLAY INVISIBLE (-1800 1025);
FORCEPROP 0 LAST CDS_LOCATION Q103
J 0
(-1625 1150);
DISPLAY 1.021277 (-1625 1150);
DISPLAY INVISIBLE (-1625 1150);
FORCEPROP 0 LAST $SEC 1
J 0
(-1625 1150);
DISPLAY 0.680851 (-1625 1150);
PAINT MONO (-1625 1150);
DISPLAY INVISIBLE (-1625 1150);
FORCEPROP 2 LAST CDS_SEC 1
J 0
(-1625 1150);
DISPLAY 1.021277 (-1625 1150);
DISPLAY INVISIBLE (-1625 1150);
FORCEADD UNIVERSAL_GND..1
(-1750 650);
FORCEPROP 3 LASTPIN (-1750 700) SIG_NAME GND\g
J 0
(-1740 710);
DISPLAY 0.659574 (-1740 710);
PAINT MONO (-1740 710);
DISPLAY INVISIBLE (-1740 710);
FORCEPROP 2 LAST CDS_LIB logical_power
J 0
(-1750 650);
DISPLAY INVISIBLE (-1750 650);
FORCEPROP 1 LAST HDL_POWER GND
J 1
(-1725 575);
DISPLAY 0.872340 (-1725 575);
PAINT GREEN (-1725 575);
DISPLAY INVISIBLE (-1725 575);
FORCEPROP 1 LAST PATH I38
J 0
(-1675 650);
DISPLAY 0.872340 (-1675 650);
PAINT AQUA (-1675 650);
DISPLAY INVISIBLE (-1675 650);
FORCEADD Q_RES..2
(-1750 1475);
FORCEPROP 1 LAST PART_NUMBER CS24702JB10
J 0
(-1710 1300);
DISPLAY 0.638298 (-1710 1300);
DISPLAY INVISIBLE (-1710 1300);
FORCEPROP 1 LAST VALUE 4.7K
J 0
(-1705 1550);
DISPLAY 0.638298 (-1705 1550);
FORCEPROP 1 LAST TOLERANCE 5%
J 0
(-1705 1500);
DISPLAY 0.638298 (-1705 1500);
FORCEPROP 1 LAST PACK_TYPE 0402LF
J 0
(-1710 1350);
DISPLAY 0.638298 (-1710 1350);
FORCEPROP 1 LAST MATERIAL CHIP
J 0
(-1710 1400);
DISPLAY 0.638298 (-1710 1400);
FORCEPROP 1 LAST WATTAGE 1/16W
J 0
(-1710 1450);
DISPLAY 0.638298 (-1710 1450);
FORCEPROP 1 LAST $LOCATION R3434
J 0
(-1705 1600);
DISPLAY 0.638298 (-1705 1600);
FORCEPROP 1 LASTPIN (-1750 1575) $PN 1
J 0
(-1745 1537);
DISPLAY 0.787234 (-1745 1537);
FORCEPROP 1 LASTPIN (-1750 1375) $PN 2
J 0
(-1745 1385);
DISPLAY 0.787234 (-1745 1385);
FORCEPROP 2 LAST CDS_LIB pure_quanta
J 0
(-1750 1475);
PAINT MONO (-1750 1475);
DISPLAY INVISIBLE (-1750 1475);
FORCEPROP 1 LAST PATH I39
J 0
(-1700 1650);
DISPLAY 0.978723 (-1700 1650);
PAINT WHITE (-1700 1650);
DISPLAY INVISIBLE (-1700 1650);
FORCEPROP 2 LAST CDS_LOCATION R3434
J 0
(-1700 1700);
DISPLAY 1.021277 (-1700 1700);
DISPLAY INVISIBLE (-1700 1700);
FORCEPROP 2 LAST $SEC 1
J 0
(-1700 1700);
DISPLAY 0.680851 (-1700 1700);
PAINT MONO (-1700 1700);
DISPLAY INVISIBLE (-1700 1700);
FORCEPROP 2 LAST CDS_SEC 1
J 0
(-1700 1700);
DISPLAY 1.021277 (-1700 1700);
DISPLAY INVISIBLE (-1700 1700);
FORCEADD MOSFET_NCH_DUAL..1
(-1800 2375);
FORCEPROP 1 LAST PART_NUMBER BAM138K0003
J 0
(-1649 2289);
DISPLAY 0.723404 (-1649 2289);
PAINT GREEN (-1649 2289);
DISPLAY INVISIBLE (-1649 2289);
FORCEPROP 1 LAST MATERIAL IC
J 0
(-1649 2224);
DISPLAY 0.723404 (-1649 2224);
PAINT GREEN (-1649 2224);
FORCEPROP 2 LAST PART_TYPE SMLF
J 0
(-1625 2450);
DISPLAY 1.021277 (-1625 2450);
FORCEPROP 2 LAST VALUE PJT138K
J 0
(-1625 2400);
DISPLAY 1.021277 (-1625 2400);
FORCEPROP 1 LAST $LOCATION Q102
J 0
(-1649 2349);
DISPLAY 0.723404 (-1649 2349);
PAINT GREEN (-1649 2349);
FORCEPROP 0 LASTPIN (-1750 2575) $PN 6
R 1
J 0
(-1760 2585);
DISPLAY 0.680851 (-1760 2585);
PAINT MONO (-1760 2585);
FORCEPROP 0 LASTPIN (-2000 2325) $PN 2
J 2
(-2010 2335);
DISPLAY 0.680851 (-2010 2335);
PAINT MONO (-2010 2335);
FORCEPROP 0 LASTPIN (-1750 2175) $PN 1
R 1
J 2
(-1760 2165);
DISPLAY 0.680851 (-1760 2165);
PAINT MONO (-1760 2165);
FORCEPROP 1 LAST PATH I40
J 0
(-1800 2375);
DISPLAY 0.723404 (-1800 2375);
PAINT GREEN (-1800 2375);
DISPLAY INVISIBLE (-1800 2375);
FORCEPROP 1 LAST CDS_LMAN_SYM_OUTLINE -150,150,150,-150
J 0
(-1800 2375);
DISPLAY 0.468085 (-1800 2375);
PAINT GREEN (-1800 2375);
DISPLAY INVISIBLE (-1800 2375);
FORCEPROP 1 LAST NEEDS_NO_SIZE TRUE
J 0
(-1800 2374);
DISPLAY 0.468085 (-1800 2374);
PAINT GREEN (-1800 2374);
DISPLAY INVISIBLE (-1800 2374);
FORCEPROP 2 LAST CDS_LIB pure_quanta
J 0
(-1800 2375);
DISPLAY INVISIBLE (-1800 2375);
FORCEPROP 0 LAST CDS_LOCATION Q102
J 0
(-1625 2500);
DISPLAY 1.021277 (-1625 2500);
DISPLAY INVISIBLE (-1625 2500);
FORCEPROP 0 LAST $SEC 1
J 0
(-1625 2500);
DISPLAY 0.680851 (-1625 2500);
PAINT MONO (-1625 2500);
DISPLAY INVISIBLE (-1625 2500);
FORCEPROP 0 LAST CDS_SEC 1
J 0
(-1625 2500);
DISPLAY 1.021277 (-1625 2500);
DISPLAY INVISIBLE (-1625 2500);
FORCEADD UNIVERSAL_POWER..1
(-1750 1775);
FORCEPROP 3 LASTPIN (-1750 1725) SIG_NAME P3V3_AUX\g
J 0
(-1740 1735);
DISPLAY 0.659574 (-1740 1735);
PAINT MONO (-1740 1735);
DISPLAY INVISIBLE (-1740 1735);
FORCEPROP 1 LAST HDL_POWER P3V3_AUX
J 1
(-1750 1825);
DISPLAY 0.872340 (-1750 1825);
PAINT GREEN (-1750 1825);
FORCEPROP 2 LAST CDS_LIB logical_power
J 0
(-1750 1775);
PAINT MONO (-1750 1775);
DISPLAY INVISIBLE (-1750 1775);
FORCEPROP 1 LAST PATH I41
J 0
(-1700 1800);
DISPLAY 0.872340 (-1700 1800);
PAINT AQUA (-1700 1800);
DISPLAY INVISIBLE (-1700 1800);
FORCEADD UNIVERSAL_GND..1
(-1750 2000);
FORCEPROP 3 LASTPIN (-1750 2050) SIG_NAME GND\g
J 0
(-1740 2060);
DISPLAY 0.659574 (-1740 2060);
PAINT MONO (-1740 2060);
DISPLAY INVISIBLE (-1740 2060);
FORCEPROP 1 LAST PATH I42
J 0
(-1675 2000);
DISPLAY 0.872340 (-1675 2000);
PAINT AQUA (-1675 2000);
DISPLAY INVISIBLE (-1675 2000);
FORCEPROP 1 LAST HDL_POWER GND
J 1
(-1725 1925);
DISPLAY 0.872340 (-1725 1925);
PAINT GREEN (-1725 1925);
DISPLAY INVISIBLE (-1725 1925);
FORCEPROP 2 LAST CDS_LIB logical_power
J 0
(-1750 2000);
DISPLAY INVISIBLE (-1750 2000);
FORCEADD MOSFET_NCH_DUAL..2
(-850 1300);
FORCEPROP 1 LAST PART_NUMBER BAM138K0003
J 0
(-699 1206);
DISPLAY 0.723404 (-699 1206);
PAINT GREEN (-699 1206);
DISPLAY INVISIBLE (-699 1206);
FORCEPROP 2 LAST PART_TYPE SMLF
J 0
(-675 1375);
DISPLAY 1.021277 (-675 1375);
FORCEPROP 1 LAST MATERIAL IC
J 0
(-699 1151);
DISPLAY 0.723404 (-699 1151);
PAINT GREEN (-699 1151);
FORCEPROP 2 LAST VALUE PJT138K
J 0
(-675 1325);
DISPLAY 1.021277 (-675 1325);
FORCEPROP 1 LAST LOCATION Q103
J 0
(-699 1276);
DISPLAY 0.723404 (-699 1276);
PAINT GREEN (-699 1276);
FORCEPROP 0 LASTPIN (-800 1500) $PN 3
R 1
J 0
(-810 1510);
DISPLAY 0.680851 (-810 1510);
PAINT MONO (-810 1510);
FORCEPROP 0 LASTPIN (-1050 1250) $PN 5
J 2
(-1060 1260);
DISPLAY 0.680851 (-1060 1260);
PAINT MONO (-1060 1260);
FORCEPROP 0 LASTPIN (-800 1100) $PN 4
R 1
J 2
(-810 1090);
DISPLAY 0.680851 (-810 1090);
PAINT MONO (-810 1090);
FORCEPROP 2 LAST CDS_LIB pure_quanta
J 0
(-850 1300);
DISPLAY INVISIBLE (-850 1300);
FORCEPROP 1 LAST NEEDS_NO_SIZE TRUE
J 0
(-700 1191);
DISPLAY 0.468085 (-700 1191);
PAINT GREEN (-700 1191);
DISPLAY INVISIBLE (-700 1191);
FORCEPROP 1 LAST CDS_LMAN_SYM_OUTLINE -150,150,150,-150
J 0
(-850 1300);
DISPLAY 0.468085 (-850 1300);
PAINT GREEN (-850 1300);
DISPLAY INVISIBLE (-850 1300);
FORCEPROP 1 LAST PATH I43
J 0
(-700 1150);
DISPLAY 0.723404 (-700 1150);
PAINT GREEN (-700 1150);
DISPLAY INVISIBLE (-700 1150);
FORCEPROP 0 LAST $SEC 2
J 0
(-675 1425);
DISPLAY 0.680851 (-675 1425);
PAINT MONO (-675 1425);
DISPLAY INVISIBLE (-675 1425);
FORCEPROP 0 LAST CDS_SEC 2
J 0
(-675 1425);
DISPLAY 1.021277 (-675 1425);
DISPLAY INVISIBLE (-675 1425);
FORCEADD UNIVERSAL_GND..1
(-800 925);
FORCEPROP 3 LASTPIN (-800 975) SIG_NAME GND\g
J 0
(-790 985);
DISPLAY 0.659574 (-790 985);
PAINT MONO (-790 985);
DISPLAY INVISIBLE (-790 985);
FORCEPROP 1 LAST HDL_POWER GND
J 1
(-775 850);
DISPLAY 0.872340 (-775 850);
PAINT GREEN (-775 850);
DISPLAY INVISIBLE (-775 850);
FORCEPROP 2 LAST CDS_LIB logical_power
J 0
(-800 925);
DISPLAY INVISIBLE (-800 925);
FORCEPROP 1 LAST PATH I44
J 0
(-725 925);
DISPLAY 0.872340 (-725 925);
PAINT AQUA (-725 925);
DISPLAY INVISIBLE (-725 925);
FORCEADD Q_RES..2
(-800 1725);
FORCEPROP 1 LAST PART_NUMBER CS24702JB10
J 0
(-760 1550);
DISPLAY 0.638298 (-760 1550);
DISPLAY INVISIBLE (-760 1550);
FORCEPROP 1 LAST VALUE 4.7K
J 0
(-755 1800);
DISPLAY 0.638298 (-755 1800);
FORCEPROP 1 LAST MATERIAL CHIP
J 0
(-760 1650);
DISPLAY 0.638298 (-760 1650);
FORCEPROP 1 LAST PACK_TYPE 0402LF
J 0
(-760 1600);
DISPLAY 0.638298 (-760 1600);
FORCEPROP 1 LAST WATTAGE 1/16W
J 0
(-760 1700);
DISPLAY 0.638298 (-760 1700);
FORCEPROP 1 LAST TOLERANCE 5%
J 0
(-755 1750);
DISPLAY 0.638298 (-755 1750);
FORCEPROP 1 LAST $LOCATION R3436
J 0
(-755 1850);
DISPLAY 0.978723 (-755 1850);
FORCEPROP 1 LASTPIN (-800 1825) $PN 1
J 0
(-795 1787);
DISPLAY 0.787234 (-795 1787);
PAINT MONO (-795 1787);
FORCEPROP 1 LASTPIN (-800 1625) $PN 2
J 0
(-795 1635);
DISPLAY 0.787234 (-795 1635);
PAINT MONO (-795 1635);
FORCEPROP 2 LAST CDS_LIB pure_quanta
J 0
(-800 1725);
DISPLAY INVISIBLE (-800 1725);
FORCEPROP 1 LAST PATH I45
J 0
(-750 1900);
DISPLAY 0.978723 (-750 1900);
PAINT WHITE (-750 1900);
DISPLAY INVISIBLE (-750 1900);
FORCEPROP 0 LAST CDS_LOCATION R3436
J 0
(-750 1900);
DISPLAY 1.021277 (-750 1900);
DISPLAY INVISIBLE (-750 1900);
FORCEPROP 0 LAST $SEC 1
J 0
(-750 1900);
DISPLAY 0.680851 (-750 1900);
PAINT MONO (-750 1900);
DISPLAY INVISIBLE (-750 1900);
FORCEPROP 0 LAST CDS_SEC 1
J 0
(-750 1900);
DISPLAY 1.021277 (-750 1900);
DISPLAY INVISIBLE (-750 1900);
FORCEADD UNIVERSAL_POWER..1
(-800 2025);
FORCEPROP 3 LASTPIN (-800 1975) SIG_NAME P3V3_AUX\g
J 0
(-790 1985);
DISPLAY 0.659574 (-790 1985);
PAINT MONO (-790 1985);
DISPLAY INVISIBLE (-790 1985);
FORCEPROP 1 LAST HDL_POWER P3V3_AUX
J 1
(-800 2075);
DISPLAY 0.872340 (-800 2075);
PAINT GREEN (-800 2075);
FORCEPROP 2 LAST CDS_LIB logical_power
J 0
(-800 2025);
DISPLAY INVISIBLE (-800 2025);
FORCEPROP 1 LAST PATH I46
J 0
(-750 2050);
DISPLAY 0.872340 (-750 2050);
PAINT AQUA (-750 2050);
DISPLAY INVISIBLE (-750 2050);
FORCEADD UNIVERSAL_GND..1
(-775 2300);
FORCEPROP 3 LASTPIN (-775 2350) SIG_NAME GND\g
J 0
(-765 2360);
DISPLAY 0.659574 (-765 2360);
PAINT MONO (-765 2360);
DISPLAY INVISIBLE (-765 2360);
FORCEPROP 1 LAST HDL_POWER GND
J 1
(-750 2225);
DISPLAY 0.872340 (-750 2225);
PAINT GREEN (-750 2225);
DISPLAY INVISIBLE (-750 2225);
FORCEPROP 2 LAST CDS_LIB logical_power
J 0
(-775 2300);
DISPLAY INVISIBLE (-775 2300);
FORCEPROP 1 LAST PATH I47
J 0
(-700 2300);
DISPLAY 0.872340 (-700 2300);
PAINT AQUA (-700 2300);
DISPLAY INVISIBLE (-700 2300);
FORCEADD MOSFET_NCH_DUAL..2
(-825 2675);
FORCEPROP 1 LAST PART_NUMBER BAM138K0003
J 0
(-674 2581);
DISPLAY 0.723404 (-674 2581);
PAINT GREEN (-674 2581);
DISPLAY INVISIBLE (-674 2581);
FORCEPROP 1 LAST MATERIAL IC
J 0
(-674 2526);
DISPLAY 0.723404 (-674 2526);
PAINT GREEN (-674 2526);
FORCEPROP 2 LAST VALUE PJT138K
J 0
(-650 2700);
DISPLAY 1.021277 (-650 2700);
FORCEPROP 2 LAST PART_TYPE SMLF
J 0
(-650 2750);
DISPLAY 1.021277 (-650 2750);
FORCEPROP 1 LAST $LOCATION Q102
J 0
(-674 2651);
DISPLAY 0.723404 (-674 2651);
PAINT GREEN (-674 2651);
FORCEPROP 0 LASTPIN (-775 2875) $PN 3
R 1
J 0
(-785 2885);
DISPLAY 0.680851 (-785 2885);
PAINT MONO (-785 2885);
FORCEPROP 0 LASTPIN (-1025 2625) $PN 5
J 2
(-1035 2635);
DISPLAY 0.680851 (-1035 2635);
PAINT MONO (-1035 2635);
FORCEPROP 0 LASTPIN (-775 2475) $PN 4
R 1
J 2
(-785 2465);
DISPLAY 0.680851 (-785 2465);
PAINT MONO (-785 2465);
FORCEPROP 2 LAST CDS_LIB pure_quanta
J 0
(-825 2675);
DISPLAY INVISIBLE (-825 2675);
FORCEPROP 1 LAST NEEDS_NO_SIZE TRUE
J 0
(-675 2566);
DISPLAY 0.468085 (-675 2566);
PAINT GREEN (-675 2566);
DISPLAY INVISIBLE (-675 2566);
FORCEPROP 1 LAST CDS_LMAN_SYM_OUTLINE -150,150,150,-150
J 0
(-825 2675);
DISPLAY 0.468085 (-825 2675);
PAINT GREEN (-825 2675);
DISPLAY INVISIBLE (-825 2675);
FORCEPROP 1 LAST PATH I48
J 0
(-675 2525);
DISPLAY 0.723404 (-675 2525);
PAINT GREEN (-675 2525);
DISPLAY INVISIBLE (-675 2525);
FORCEPROP 0 LAST CDS_LOCATION Q102
J 0
(-650 2800);
DISPLAY 1.021277 (-650 2800);
DISPLAY INVISIBLE (-650 2800);
FORCEPROP 0 LAST $SEC 2
J 0
(-650 2800);
DISPLAY 0.680851 (-650 2800);
PAINT MONO (-650 2800);
DISPLAY INVISIBLE (-650 2800);
FORCEPROP 0 LAST CDS_SEC 2
J 0
(-650 2800);
DISPLAY 1.021277 (-650 2800);
DISPLAY INVISIBLE (-650 2800);
FORCEADD Q_RES..2
(-1775 2825);
FORCEPROP 1 LAST PART_NUMBER CS24702JB10
J 0
(-1735 2650);
DISPLAY 0.638298 (-1735 2650);
DISPLAY INVISIBLE (-1735 2650);
FORCEPROP 1 LAST PACK_TYPE 0402LF
J 0
(-1735 2700);
DISPLAY 0.638298 (-1735 2700);
FORCEPROP 1 LAST MATERIAL CHIP
J 0
(-1735 2750);
DISPLAY 0.638298 (-1735 2750);
FORCEPROP 1 LAST WATTAGE 1/16W
J 0
(-1735 2800);
DISPLAY 0.638298 (-1735 2800);
FORCEPROP 1 LAST TOLERANCE 5%
J 0
(-1730 2850);
DISPLAY 0.638298 (-1730 2850);
FORCEPROP 1 LAST VALUE 4.7K
J 0
(-1730 2900);
DISPLAY 0.638298 (-1730 2900);
FORCEPROP 1 LAST $LOCATION R3433
J 0
(-1730 2950);
DISPLAY 0.638298 (-1730 2950);
FORCEPROP 1 LASTPIN (-1775 2925) $PN 1
J 0
(-1770 2887);
DISPLAY 0.787234 (-1770 2887);
FORCEPROP 1 LASTPIN (-1775 2725) $PN 2
J 0
(-1770 2735);
DISPLAY 0.787234 (-1770 2735);
FORCEPROP 2 LAST CDS_LIB pure_quanta
J 0
(-1775 2825);
PAINT MONO (-1775 2825);
DISPLAY INVISIBLE (-1775 2825);
FORCEPROP 1 LAST PATH I49
J 0
(-1725 3000);
DISPLAY 0.978723 (-1725 3000);
PAINT WHITE (-1725 3000);
DISPLAY INVISIBLE (-1725 3000);
FORCEPROP 2 LAST CDS_LOCATION R3433
J 0
(-1725 3050);
DISPLAY 1.021277 (-1725 3050);
DISPLAY INVISIBLE (-1725 3050);
FORCEPROP 2 LAST $SEC 1
J 0
(-1725 3050);
DISPLAY 0.680851 (-1725 3050);
PAINT MONO (-1725 3050);
DISPLAY INVISIBLE (-1725 3050);
FORCEPROP 2 LAST CDS_SEC 1
J 0
(-1725 3050);
DISPLAY 1.021277 (-1725 3050);
DISPLAY INVISIBLE (-1725 3050);
FORCEADD UNIVERSAL_POWER..1
(-2975 -75);
FORCEPROP 3 LASTPIN (-2975 -125) SIG_NAME P3V3_AUX\g
J 0
(-2965 -115);
DISPLAY 0.659574 (-2965 -115);
PAINT MONO (-2965 -115);
DISPLAY INVISIBLE (-2965 -115);
FORCEPROP 1 LAST HDL_POWER P3V3_AUX
J 1
(-2975 -25);
DISPLAY 0.872340 (-2975 -25);
PAINT GREEN (-2975 -25);
FORCEPROP 1 LAST PATH I5
J 0
(-2925 -50);
DISPLAY 0.872340 (-2925 -50);
PAINT AQUA (-2925 -50);
DISPLAY INVISIBLE (-2925 -50);
FORCEPROP 2 LAST CDS_LIB logical_power
J 0
(-2975 -75);
PAINT MONO (-2975 -75);
DISPLAY INVISIBLE (-2975 -75);
FORCEADD UNIVERSAL_POWER..1
(-1775 3125);
FORCEPROP 3 LASTPIN (-1775 3075) SIG_NAME P3V3_AUX\g
J 0
(-1765 3085);
DISPLAY 0.659574 (-1765 3085);
PAINT MONO (-1765 3085);
DISPLAY INVISIBLE (-1765 3085);
FORCEPROP 1 LAST HDL_POWER P3V3_AUX
J 1
(-1775 3175);
DISPLAY 0.872340 (-1775 3175);
PAINT GREEN (-1775 3175);
FORCEPROP 2 LAST CDS_LIB logical_power
J 0
(-1775 3125);
PAINT MONO (-1775 3125);
DISPLAY INVISIBLE (-1775 3125);
FORCEPROP 1 LAST PATH I50
J 0
(-1725 3150);
DISPLAY 0.872340 (-1725 3150);
PAINT AQUA (-1725 3150);
DISPLAY INVISIBLE (-1725 3150);
FORCEADD UNIVERSAL_GND..1
(-1825 3400);
FORCEPROP 3 LASTPIN (-1825 3450) SIG_NAME GND\g
J 0
(-1815 3460);
DISPLAY 0.659574 (-1815 3460);
PAINT MONO (-1815 3460);
DISPLAY INVISIBLE (-1815 3460);
FORCEPROP 1 LAST PATH I51
J 0
(-1750 3400);
DISPLAY 0.872340 (-1750 3400);
PAINT AQUA (-1750 3400);
DISPLAY INVISIBLE (-1750 3400);
FORCEPROP 2 LAST CDS_LIB logical_power
J 0
(-1825 3400);
DISPLAY INVISIBLE (-1825 3400);
FORCEPROP 1 LAST HDL_POWER GND
J 1
(-1800 3325);
DISPLAY 0.872340 (-1800 3325);
PAINT GREEN (-1800 3325);
DISPLAY INVISIBLE (-1800 3325);
FORCEADD MOSFET_NCH_DUAL..1
(-1875 3775);
FORCEPROP 1 LAST PART_NUMBER BAM138K0003
J 0
(-1724 3689);
DISPLAY 0.723404 (-1724 3689);
PAINT GREEN (-1724 3689);
DISPLAY INVISIBLE (-1724 3689);
FORCEPROP 1 LAST MATERIAL IC
J 0
(-1724 3624);
DISPLAY 0.723404 (-1724 3624);
PAINT GREEN (-1724 3624);
FORCEPROP 2 LAST PART_TYPE SMLF
J 0
(-1700 3850);
DISPLAY 1.021277 (-1700 3850);
FORCEPROP 2 LAST VALUE PJT138K
J 0
(-1700 3800);
DISPLAY 1.021277 (-1700 3800);
FORCEPROP 1 LAST $LOCATION Q101
J 0
(-1724 3749);
DISPLAY 0.723404 (-1724 3749);
PAINT GREEN (-1724 3749);
FORCEPROP 0 LASTPIN (-1825 3975) $PN 6
R 1
J 0
(-1835 3985);
DISPLAY 0.680851 (-1835 3985);
PAINT MONO (-1835 3985);
FORCEPROP 0 LASTPIN (-2075 3725) $PN 2
J 2
(-2085 3735);
DISPLAY 0.680851 (-2085 3735);
PAINT MONO (-2085 3735);
FORCEPROP 0 LASTPIN (-1825 3575) $PN 1
R 1
J 2
(-1835 3565);
DISPLAY 0.680851 (-1835 3565);
PAINT MONO (-1835 3565);
FORCEPROP 1 LAST PATH I52
J 0
(-1875 3775);
DISPLAY 0.723404 (-1875 3775);
PAINT GREEN (-1875 3775);
DISPLAY INVISIBLE (-1875 3775);
FORCEPROP 1 LAST CDS_LMAN_SYM_OUTLINE -150,150,150,-150
J 0
(-1875 3775);
DISPLAY 0.468085 (-1875 3775);
PAINT GREEN (-1875 3775);
DISPLAY INVISIBLE (-1875 3775);
FORCEPROP 1 LAST NEEDS_NO_SIZE TRUE
J 0
(-1875 3774);
DISPLAY 0.468085 (-1875 3774);
PAINT GREEN (-1875 3774);
DISPLAY INVISIBLE (-1875 3774);
FORCEPROP 2 LAST CDS_LIB pure_quanta
J 0
(-1875 3775);
DISPLAY INVISIBLE (-1875 3775);
FORCEPROP 2 LAST CDS_LOCATION Q101
J 0
(-1700 3900);
DISPLAY 1.021277 (-1700 3900);
DISPLAY INVISIBLE (-1700 3900);
FORCEPROP 0 LAST $SEC 1
J 0
(-1700 3900);
DISPLAY 0.680851 (-1700 3900);
PAINT MONO (-1700 3900);
DISPLAY INVISIBLE (-1700 3900);
FORCEPROP 2 LAST CDS_SEC 1
J 0
(-1700 3900);
DISPLAY 1.021277 (-1700 3900);
DISPLAY INVISIBLE (-1700 3900);
FORCEADD Q_RES..2
(-1825 4375);
FORCEPROP 1 LAST PART_NUMBER CS24702JB10
J 0
(-1785 4200);
DISPLAY 0.638298 (-1785 4200);
DISPLAY INVISIBLE (-1785 4200);
FORCEPROP 1 LAST PACK_TYPE 0402LF
J 0
(-1785 4250);
DISPLAY 0.638298 (-1785 4250);
FORCEPROP 1 LAST TOLERANCE 5%
J 0
(-1780 4400);
DISPLAY 0.638298 (-1780 4400);
FORCEPROP 1 LAST WATTAGE 1/16W
J 0
(-1785 4350);
DISPLAY 0.638298 (-1785 4350);
FORCEPROP 1 LAST VALUE 4.7K
J 0
(-1780 4450);
DISPLAY 0.638298 (-1780 4450);
FORCEPROP 1 LAST MATERIAL CHIP
J 0
(-1785 4300);
DISPLAY 0.638298 (-1785 4300);
FORCEPROP 1 LAST $LOCATION R3432
J 0
(-1780 4500);
DISPLAY 0.638298 (-1780 4500);
FORCEPROP 1 LASTPIN (-1825 4475) $PN 1
J 0
(-1820 4437);
DISPLAY 0.787234 (-1820 4437);
FORCEPROP 1 LASTPIN (-1825 4275) $PN 2
J 0
(-1820 4285);
DISPLAY 0.787234 (-1820 4285);
FORCEPROP 1 LAST PATH I53
J 0
(-1775 4550);
DISPLAY 0.978723 (-1775 4550);
PAINT WHITE (-1775 4550);
DISPLAY INVISIBLE (-1775 4550);
FORCEPROP 2 LAST CDS_LIB pure_quanta
J 0
(-1825 4375);
PAINT MONO (-1825 4375);
DISPLAY INVISIBLE (-1825 4375);
FORCEPROP 2 LAST CDS_LOCATION R3432
J 0
(-1775 4600);
DISPLAY 1.021277 (-1775 4600);
DISPLAY INVISIBLE (-1775 4600);
FORCEPROP 2 LAST $SEC 1
J 0
(-1775 4600);
DISPLAY 0.680851 (-1775 4600);
PAINT MONO (-1775 4600);
DISPLAY INVISIBLE (-1775 4600);
FORCEPROP 2 LAST CDS_SEC 1
J 0
(-1775 4600);
DISPLAY 1.021277 (-1775 4600);
DISPLAY INVISIBLE (-1775 4600);
FORCEADD UNIVERSAL_POWER..1
(-1825 4600);
FORCEPROP 3 LASTPIN (-1825 4550) SIG_NAME P3V3_AUX\g
J 0
(-1815 4560);
DISPLAY 0.659574 (-1815 4560);
PAINT MONO (-1815 4560);
DISPLAY INVISIBLE (-1815 4560);
FORCEPROP 1 LAST HDL_POWER P3V3_AUX
J 1
(-1825 4650);
DISPLAY 0.872340 (-1825 4650);
PAINT GREEN (-1825 4650);
FORCEPROP 1 LAST PATH I54
J 0
(-1775 4625);
DISPLAY 0.872340 (-1775 4625);
PAINT AQUA (-1775 4625);
DISPLAY INVISIBLE (-1775 4625);
FORCEPROP 2 LAST CDS_LIB logical_power
J 0
(-1825 4600);
PAINT MONO (-1825 4600);
DISPLAY INVISIBLE (-1825 4600);
FORCEADD Q_RES..2
(-775 3100);
FORCEPROP 1 LAST PART_NUMBER CS24702JB10
J 0
(-735 2925);
DISPLAY 0.638298 (-735 2925);
DISPLAY INVISIBLE (-735 2925);
FORCEPROP 1 LAST MATERIAL CHIP
J 0
(-735 3025);
DISPLAY 0.638298 (-735 3025);
FORCEPROP 1 LAST TOLERANCE 5%
J 0
(-730 3125);
DISPLAY 0.638298 (-730 3125);
FORCEPROP 1 LAST VALUE 4.7K
J 0
(-730 3175);
DISPLAY 0.638298 (-730 3175);
FORCEPROP 1 LAST PACK_TYPE 0402LF
J 0
(-735 2975);
DISPLAY 0.638298 (-735 2975);
FORCEPROP 1 LAST WATTAGE 1/16W
J 0
(-735 3075);
DISPLAY 0.638298 (-735 3075);
FORCEPROP 1 LAST $LOCATION R3438
J 0
(-730 3225);
DISPLAY 0.638298 (-730 3225);
FORCEPROP 1 LASTPIN (-775 3200) $PN 1
J 0
(-770 3162);
DISPLAY 0.787234 (-770 3162);
FORCEPROP 1 LASTPIN (-775 3000) $PN 2
J 0
(-770 3010);
DISPLAY 0.787234 (-770 3010);
FORCEPROP 2 LAST CDS_LIB pure_quanta
J 0
(-775 3100);
PAINT MONO (-775 3100);
DISPLAY INVISIBLE (-775 3100);
FORCEPROP 1 LAST PATH I55
J 0
(-725 3275);
DISPLAY 0.978723 (-725 3275);
PAINT WHITE (-725 3275);
DISPLAY INVISIBLE (-725 3275);
FORCEPROP 2 LAST CDS_LOCATION R3438
J 0
(-725 3325);
DISPLAY 1.021277 (-725 3325);
DISPLAY INVISIBLE (-725 3325);
FORCEPROP 2 LAST $SEC 1
J 0
(-725 3325);
DISPLAY 0.680851 (-725 3325);
PAINT MONO (-725 3325);
DISPLAY INVISIBLE (-725 3325);
FORCEPROP 2 LAST CDS_SEC 1
J 0
(-725 3325);
DISPLAY 1.021277 (-725 3325);
DISPLAY INVISIBLE (-725 3325);
FORCEADD UNIVERSAL_POWER..1
(-775 3325);
FORCEPROP 3 LASTPIN (-775 3275) SIG_NAME P3V3_AUX\g
J 0
(-765 3285);
DISPLAY 0.659574 (-765 3285);
PAINT MONO (-765 3285);
DISPLAY INVISIBLE (-765 3285);
FORCEPROP 1 LAST HDL_POWER P3V3_AUX
J 1
(-775 3375);
DISPLAY 0.872340 (-775 3375);
PAINT GREEN (-775 3375);
FORCEPROP 2 LAST CDS_LIB logical_power
J 0
(-775 3325);
PAINT MONO (-775 3325);
DISPLAY INVISIBLE (-775 3325);
FORCEPROP 1 LAST PATH I56
J 0
(-725 3350);
DISPLAY 0.872340 (-725 3350);
PAINT AQUA (-725 3350);
DISPLAY INVISIBLE (-725 3350);
FORCEADD MOSFET_NCH_DUAL..2
(-725 4075);
FORCEPROP 1 LAST PART_NUMBER BAM138K0003
J 0
(-574 3981);
DISPLAY 0.723404 (-574 3981);
PAINT GREEN (-574 3981);
DISPLAY INVISIBLE (-574 3981);
FORCEPROP 1 LAST MATERIAL IC
J 0
(-574 3926);
DISPLAY 0.723404 (-574 3926);
PAINT GREEN (-574 3926);
FORCEPROP 2 LAST VALUE PJT138K
J 0
(-550 4100);
DISPLAY 1.021277 (-550 4100);
FORCEPROP 2 LAST PART_TYPE SMLF
J 0
(-550 4150);
DISPLAY 1.021277 (-550 4150);
FORCEPROP 1 LAST $LOCATION Q101
J 0
(-574 4051);
DISPLAY 0.723404 (-574 4051);
PAINT GREEN (-574 4051);
FORCEPROP 0 LASTPIN (-675 4275) $PN 3
R 1
J 0
(-685 4285);
DISPLAY 0.680851 (-685 4285);
PAINT MONO (-685 4285);
FORCEPROP 0 LASTPIN (-925 4025) $PN 5
J 2
(-935 4035);
DISPLAY 0.680851 (-935 4035);
PAINT MONO (-935 4035);
FORCEPROP 0 LASTPIN (-675 3875) $PN 4
R 1
J 2
(-685 3865);
DISPLAY 0.680851 (-685 3865);
PAINT MONO (-685 3865);
FORCEPROP 2 LAST CDS_LIB pure_quanta
J 0
(-725 4075);
DISPLAY INVISIBLE (-725 4075);
FORCEPROP 1 LAST NEEDS_NO_SIZE TRUE
J 0
(-575 3966);
DISPLAY 0.468085 (-575 3966);
PAINT GREEN (-575 3966);
DISPLAY INVISIBLE (-575 3966);
FORCEPROP 1 LAST CDS_LMAN_SYM_OUTLINE -150,150,150,-150
J 0
(-725 4075);
DISPLAY 0.468085 (-725 4075);
PAINT GREEN (-725 4075);
DISPLAY INVISIBLE (-725 4075);
FORCEPROP 1 LAST PATH I57
J 0
(-575 3925);
DISPLAY 0.723404 (-575 3925);
PAINT GREEN (-575 3925);
DISPLAY INVISIBLE (-575 3925);
FORCEPROP 0 LAST CDS_LOCATION Q101
J 0
(-550 4200);
DISPLAY 1.021277 (-550 4200);
DISPLAY INVISIBLE (-550 4200);
FORCEPROP 0 LAST $SEC 2
J 0
(-550 4200);
DISPLAY 0.680851 (-550 4200);
PAINT MONO (-550 4200);
DISPLAY INVISIBLE (-550 4200);
FORCEPROP 0 LAST CDS_SEC 2
J 0
(-550 4200);
DISPLAY 1.021277 (-550 4200);
DISPLAY INVISIBLE (-550 4200);
FORCEADD UNIVERSAL_GND..1
(-675 3700);
FORCEPROP 3 LASTPIN (-675 3750) SIG_NAME GND\g
J 0
(-665 3760);
DISPLAY 0.659574 (-665 3760);
PAINT MONO (-665 3760);
DISPLAY INVISIBLE (-665 3760);
FORCEPROP 2 LAST CDS_LIB logical_power
J 0
(-675 3700);
DISPLAY INVISIBLE (-675 3700);
FORCEPROP 1 LAST PATH I58
J 0
(-600 3700);
DISPLAY 0.872340 (-600 3700);
PAINT AQUA (-600 3700);
DISPLAY INVISIBLE (-600 3700);
FORCEPROP 1 LAST HDL_POWER GND
J 1
(-650 3625);
DISPLAY 0.872340 (-650 3625);
PAINT GREEN (-650 3625);
DISPLAY INVISIBLE (-650 3625);
FORCEADD Q_RES..2
(-675 4500);
FORCEPROP 1 LAST PART_NUMBER CS24702JB10
J 0
(-635 4325);
DISPLAY 0.638298 (-635 4325);
DISPLAY INVISIBLE (-635 4325);
FORCEPROP 1 LAST VALUE 4.7K
J 0
(-630 4575);
DISPLAY 0.638298 (-630 4575);
FORCEPROP 1 LAST WATTAGE 1/16W
J 0
(-635 4475);
DISPLAY 0.638298 (-635 4475);
FORCEPROP 1 LAST TOLERANCE 5%
J 0
(-630 4525);
DISPLAY 0.638298 (-630 4525);
FORCEPROP 1 LAST MATERIAL CHIP
J 0
(-635 4425);
DISPLAY 0.638298 (-635 4425);
FORCEPROP 1 LAST PACK_TYPE 0402LF
J 0
(-635 4375);
DISPLAY 0.638298 (-635 4375);
FORCEPROP 1 LAST $LOCATION R3439
J 0
(-630 4625);
DISPLAY 0.638298 (-630 4625);
FORCEPROP 1 LASTPIN (-675 4600) $PN 1
J 0
(-670 4562);
DISPLAY 0.787234 (-670 4562);
FORCEPROP 1 LASTPIN (-675 4400) $PN 2
J 0
(-670 4410);
DISPLAY 0.787234 (-670 4410);
FORCEPROP 2 LAST CDS_LIB pure_quanta
J 0
(-675 4500);
PAINT MONO (-675 4500);
DISPLAY INVISIBLE (-675 4500);
FORCEPROP 1 LAST PATH I59
J 0
(-625 4675);
DISPLAY 0.978723 (-625 4675);
PAINT WHITE (-625 4675);
DISPLAY INVISIBLE (-625 4675);
FORCEPROP 2 LAST CDS_LOCATION R3439
J 0
(-625 4725);
DISPLAY 1.021277 (-625 4725);
DISPLAY INVISIBLE (-625 4725);
FORCEPROP 2 LAST $SEC 1
J 0
(-625 4725);
DISPLAY 0.680851 (-625 4725);
PAINT MONO (-625 4725);
DISPLAY INVISIBLE (-625 4725);
FORCEPROP 2 LAST CDS_SEC 1
J 0
(-625 4725);
DISPLAY 1.021277 (-625 4725);
DISPLAY INVISIBLE (-625 4725);
FORCEADD OFFPAGE..4
R 2
(-3175 975);
FORCEPROP 2 LAST $XR0 141 
J 0
(-3427 975);
DISPLAY 0.638298 (-3427 975);
PAINT MONO (-3427 975);
FORCEPROP 1 LAST OFFPAGE TRUE
J 2
(-3500 850);
DISPLAY 0.872340 (-3500 850);
PAINT GREEN (-3500 850);
DISPLAY INVISIBLE (-3500 850);
FORCEPROP 1 LAST COMMENT_BODY TRUE
J 2
(-3150 875);
DISPLAY 0.872340 (-3150 875);
PAINT GREEN (-3150 875);
DISPLAY INVISIBLE (-3150 875);
FORCEPROP 2 LAST CDS_LIB standard
J 0
(-3175 975);
DISPLAY INVISIBLE (-3175 975);
FORCEPROP 2 LAST PATH I6
J 0
(-3425 1025);
DISPLAY 1.021277 (-3425 1025);
DISPLAY INVISIBLE (-3425 1025);
FORCEADD UNIVERSAL_GND..1
(100 1100);
FORCEPROP 3 LASTPIN (100 1150) SIG_NAME GND\g
J 0
(110 1160);
DISPLAY 0.659574 (110 1160);
PAINT MONO (110 1160);
DISPLAY INVISIBLE (110 1160);
FORCEPROP 1 LAST HDL_POWER GND
J 1
(125 1025);
DISPLAY 0.872340 (125 1025);
PAINT GREEN (125 1025);
DISPLAY INVISIBLE (125 1025);
FORCEPROP 2 LAST CDS_LIB logical_power
J 0
(100 1100);
DISPLAY INVISIBLE (100 1100);
FORCEPROP 1 LAST PATH I60
J 0
(175 1100);
DISPLAY 0.872340 (175 1100);
PAINT AQUA (175 1100);
DISPLAY INVISIBLE (175 1100);
FORCEADD UNIVERSAL_GND..1
(50 2450);
FORCEPROP 3 LASTPIN (50 2500) SIG_NAME GND\g
J 0
(60 2510);
DISPLAY 0.659574 (60 2510);
PAINT MONO (60 2510);
DISPLAY INVISIBLE (60 2510);
FORCEPROP 1 LAST HDL_POWER GND
J 1
(75 2375);
DISPLAY 0.872340 (75 2375);
PAINT GREEN (75 2375);
DISPLAY INVISIBLE (75 2375);
FORCEPROP 2 LAST CDS_LIB logical_power
J 0
(50 2450);
DISPLAY INVISIBLE (50 2450);
FORCEPROP 1 LAST PATH I61
J 0
(125 2450);
DISPLAY 0.872340 (125 2450);
PAINT AQUA (125 2450);
DISPLAY INVISIBLE (125 2450);
FORCEADD OFFPAGE..2
(350 1550);
FORCEPROP 2 LAST $XR0 213 
J 0
(539 1550);
DISPLAY 0.638298 (539 1550);
PAINT MONO (539 1550);
FORCEPROP 1 LAST COMMENT_BODY TRUE
J 0
(305 1455);
DISPLAY 0.872340 (305 1455);
PAINT GREEN (305 1455);
DISPLAY INVISIBLE (305 1455);
FORCEPROP 1 LAST OFFPAGE TRUE
J 0
(675 1425);
DISPLAY 0.872340 (675 1425);
PAINT AQUA (675 1425);
DISPLAY INVISIBLE (675 1425);
FORCEPROP 2 LAST CDS_LIB standard
J 0
(350 1550);
DISPLAY INVISIBLE (350 1550);
FORCEPROP 2 LAST PATH I62
J 0
(550 1600);
DISPLAY 1.021277 (550 1600);
DISPLAY INVISIBLE (550 1600);
FORCEADD UNIVERSAL_GND..1
(-2900 600);
FORCEPROP 3 LASTPIN (-2900 650) SIG_NAME GND\g
J 0
(-2890 660);
DISPLAY 0.659574 (-2890 660);
PAINT MONO (-2890 660);
DISPLAY INVISIBLE (-2890 660);
FORCEPROP 1 LAST PATH I7
J 0
(-2825 600);
DISPLAY 0.872340 (-2825 600);
PAINT AQUA (-2825 600);
DISPLAY INVISIBLE (-2825 600);
FORCEPROP 2 LAST CDS_LIB logical_power
J 0
(-2900 600);
DISPLAY INVISIBLE (-2900 600);
FORCEPROP 1 LAST HDL_POWER GND
J 1
(-2875 525);
DISPLAY 0.872340 (-2875 525);
PAINT GREEN (-2875 525);
DISPLAY INVISIBLE (-2875 525);
FORCEADD Q_CAP..1
(50 2650);
FORCEPROP 1 LAST PART_NUMBER TMP_QCH21006JB10
J 0
(100 2500);
DISPLAY 0.638298 (100 2500);
DISPLAY INVISIBLE (100 2500);
FORCEPROP 1 LAST VOLTAGE 50V
J 0
(100 2650);
DISPLAY 0.638298 (100 2650);
FORCEPROP 1 LAST TOLERANCE 5%
J 0
(100 2600);
DISPLAY 0.638298 (100 2600);
FORCEPROP 1 LAST MATERIAL EMPTY
J 0
(100 2550);
DISPLAY 0.638298 (100 2550);
PAINT RED (100 2550);
FORCEPROP 1 LAST VALUE 1000PF
J 0
(100 2700);
DISPLAY 0.638298 (100 2700);
FORCEPROP 1 LAST PACK_TYPE 0402
J 0
(100 2450);
DISPLAY 0.638298 (100 2450);
FORCEPROP 1 LAST $LOCATION C1973
J 0
(100 2750);
DISPLAY 0.978723 (100 2750);
FORCEPROP 1 LASTPIN (50 2750) $PN 1
J 0
(60 2730);
DISPLAY 0.787234 (60 2730);
PAINT MONO (60 2730);
FORCEPROP 1 LASTPIN (50 2550) $PN 2
J 0
(60 2530);
DISPLAY 0.787234 (60 2530);
PAINT MONO (60 2530);
FORCEPROP 2 LAST CDS_LIB pure_quanta
J 0
(50 2650);
DISPLAY INVISIBLE (50 2650);
FORCEPROP 1 LAST PATH I71
J 0
(100 2800);
DISPLAY 0.978723 (100 2800);
PAINT WHITE (100 2800);
DISPLAY INVISIBLE (100 2800);
FORCEPROP 0 LAST CDS_LOCATION C1973
J 0
(100 2800);
DISPLAY 1.021277 (100 2800);
DISPLAY INVISIBLE (100 2800);
FORCEPROP 0 LAST $SEC 1
J 0
(100 2800);
DISPLAY 0.680851 (100 2800);
PAINT MONO (100 2800);
DISPLAY INVISIBLE (100 2800);
FORCEPROP 0 LAST CDS_SEC 1
J 0
(100 2800);
DISPLAY 1.021277 (100 2800);
DISPLAY INVISIBLE (100 2800);
FORCEADD OFFPAGE..2
(250 2900);
FORCEPROP 2 LAST $XR0 213 
J 0
(439 2900);
DISPLAY 0.638298 (439 2900);
PAINT MONO (439 2900);
FORCEPROP 1 LAST COMMENT_BODY TRUE
J 0
(205 2805);
DISPLAY 0.872340 (205 2805);
PAINT GREEN (205 2805);
DISPLAY INVISIBLE (205 2805);
FORCEPROP 1 LAST OFFPAGE TRUE
J 0
(575 2775);
DISPLAY 0.872340 (575 2775);
PAINT AQUA (575 2775);
DISPLAY INVISIBLE (575 2775);
FORCEPROP 2 LAST CDS_LIB standard
J 0
(250 2900);
DISPLAY INVISIBLE (250 2900);
FORCEPROP 2 LAST PATH I72
J 0
(450 2950);
DISPLAY 1.021277 (450 2950);
DISPLAY INVISIBLE (450 2950);
FORCEADD UNIVERSAL_GND..1
(100 3825);
FORCEPROP 3 LASTPIN (100 3875) SIG_NAME GND\g
J 0
(110 3885);
DISPLAY 0.659574 (110 3885);
PAINT MONO (110 3885);
DISPLAY INVISIBLE (110 3885);
FORCEPROP 2 LAST CDS_LIB logical_power
J 0
(100 3825);
DISPLAY INVISIBLE (100 3825);
FORCEPROP 1 LAST HDL_POWER GND
J 1
(125 3750);
DISPLAY 0.872340 (125 3750);
PAINT GREEN (125 3750);
DISPLAY INVISIBLE (125 3750);
FORCEPROP 1 LAST PATH I73
J 0
(175 3825);
DISPLAY 0.872340 (175 3825);
PAINT AQUA (175 3825);
DISPLAY INVISIBLE (175 3825);
FORCEADD Q_CAP..1
(100 4025);
FORCEPROP 1 LAST PART_NUMBER TMP_QCH21006JB10
J 0
(150 3875);
DISPLAY 0.638298 (150 3875);
DISPLAY INVISIBLE (150 3875);
FORCEPROP 1 LAST VALUE 1000PF
J 0
(150 4075);
DISPLAY 0.638298 (150 4075);
FORCEPROP 1 LAST VOLTAGE 50V
J 0
(150 4025);
DISPLAY 0.638298 (150 4025);
FORCEPROP 1 LAST TOLERANCE 5%
J 0
(150 3975);
DISPLAY 0.638298 (150 3975);
FORCEPROP 1 LAST MATERIAL EMPTY
J 0
(150 3925);
DISPLAY 0.638298 (150 3925);
PAINT RED (150 3925);
FORCEPROP 1 LAST PACK_TYPE 0402
J 0
(150 3825);
DISPLAY 0.638298 (150 3825);
FORCEPROP 1 LAST $LOCATION C1974
J 0
(150 4125);
DISPLAY 0.978723 (150 4125);
FORCEPROP 1 LASTPIN (100 4125) $PN 1
J 0
(110 4105);
DISPLAY 0.787234 (110 4105);
PAINT MONO (110 4105);
FORCEPROP 1 LASTPIN (100 3925) $PN 2
J 0
(110 3905);
DISPLAY 0.787234 (110 3905);
PAINT MONO (110 3905);
FORCEPROP 2 LAST CDS_LIB pure_quanta
J 0
(100 4025);
DISPLAY INVISIBLE (100 4025);
FORCEPROP 1 LAST PATH I74
J 0
(150 4175);
DISPLAY 0.978723 (150 4175);
PAINT WHITE (150 4175);
DISPLAY INVISIBLE (150 4175);
FORCEPROP 0 LAST CDS_LOCATION C1974
J 0
(150 4175);
DISPLAY 1.021277 (150 4175);
DISPLAY INVISIBLE (150 4175);
FORCEPROP 0 LAST $SEC 1
J 0
(150 4175);
DISPLAY 0.680851 (150 4175);
PAINT MONO (150 4175);
DISPLAY INVISIBLE (150 4175);
FORCEPROP 0 LAST CDS_SEC 1
J 0
(150 4175);
DISPLAY 1.021277 (150 4175);
DISPLAY INVISIBLE (150 4175);
FORCEADD OFFPAGE..2
(450 4325);
FORCEPROP 2 LAST $XR0 213 
J 0
(639 4325);
DISPLAY 0.638298 (639 4325);
PAINT MONO (639 4325);
FORCEPROP 2 LAST CDS_LIB standard
J 0
(450 4325);
DISPLAY INVISIBLE (450 4325);
FORCEPROP 2 LAST PATH I75
J 0
(650 4375);
DISPLAY 1.021277 (650 4375);
DISPLAY INVISIBLE (650 4375);
FORCEPROP 1 LAST COMMENT_BODY TRUE
J 0
(405 4230);
DISPLAY 0.872340 (405 4230);
PAINT GREEN (405 4230);
DISPLAY INVISIBLE (405 4230);
FORCEPROP 1 LAST OFFPAGE TRUE
J 0
(775 4200);
DISPLAY 0.872340 (775 4200);
PAINT AQUA (775 4200);
DISPLAY INVISIBLE (775 4200);
FORCEADD UNIVERSAL_POWER..1
(-675 4725);
FORCEPROP 3 LASTPIN (-675 4675) SIG_NAME P3V3_AUX\g
J 0
(-665 4685);
DISPLAY 0.659574 (-665 4685);
PAINT MONO (-665 4685);
DISPLAY INVISIBLE (-665 4685);
FORCEPROP 1 LAST HDL_POWER P3V3_AUX
J 1
(-675 4775);
DISPLAY 0.872340 (-675 4775);
PAINT GREEN (-675 4775);
FORCEPROP 2 LAST CDS_LIB logical_power
J 0
(-675 4725);
PAINT MONO (-675 4725);
DISPLAY INVISIBLE (-675 4725);
FORCEPROP 1 LAST PATH I83
J 0
(-625 4750);
DISPLAY 0.872340 (-625 4750);
PAINT AQUA (-625 4750);
DISPLAY INVISIBLE (-625 4750);
FORCEADD QUANTA_TITLE_BLOCK_C..1
(5475 -1450);
FORCEPROP 0 LAST CDS_CON_LAST_MODIFIED Fri Aug 25 14:02:08 2023
J 0
(3590 -1435);
PAINT MONO (3590 -1435);
DISPLAY INVISIBLE (3590 -1435);
FORCEPROP 2 LAST CUSTOM_TXT_CDS <XR_PAGE_TITLE>
J 0
(-2415 3800);
DISPLAY 0.638298 (-2415 3800);
PAINT PINK (-2415 3800);
DISPLAY INVISIBLE (-2415 3800);
FORCEPROP 2 LAST CUSTOM_TXT_CDS <CON_LAST_MODIFIED>
J 0
(3590 -1435);
DISPLAY 0.978723 (3590 -1435);
FORCEPROP 2 LAST CUSTOM_TXT_CDS <Q_REV>
J 0
(5291 -1347);
DISPLAY 1.212766 (5291 -1347);
FORCEPROP 2 LAST CUSTOM_TXT_CDS <CON_PAGE_NUM> OF <CON_TOTAL_PAGES>
J 0
(5029 -1432);
DISPLAY 0.978723 (5029 -1432);
FORCEPROP 2 LAST CUSTOM_TXT_CDS <Q_NUMBER>
J 0
(4072 -1347);
DISPLAY 1.212766 (4072 -1347);
FORCEPROP 2 LAST CUSTOM_TXT_CDS <Q_PROJ>
J 0
(3093 -1348);
DISPLAY 1.212766 (3093 -1348);
FORCEPROP 2 LAST CUSTOM_TXT_CDS <NAME_2>
J 0
(2300 -1400);
FORCEPROP 2 LAST CUSTOM_TXT_CDS <NAME_1>
J 0
(2300 -1275);
FORCEPROP 1 LAST Q_TITLE EXAMAX_ISO (3/7)
J 0
(-3775 -1400);
DISPLAY 2.446809 (-3775 -1400);
PAINT GREEN (-3775 -1400);
FORCEPROP 1 LAST Q_DEPT 
J 1
(1712 -1401);
DISPLAY 1.957447 (1712 -1401);
PAINT GREEN (1712 -1401);
FORCEPROP 2 LAST CDS_XR_PAGE_TITLE CR-147 : @S9S_MB_2U_LIB.S9S_MB_2U(SCH_1):PAGE147
J 0
(-2415 3800);
DISPLAY 0.638298 (-2415 3800);
PAINT PINK (-2415 3800);
DISPLAY INVISIBLE (-2415 3800);
FORCEPROP 2 LAST PAGE_BORDER TRUE
J 0
(-2415 3800);
DISPLAY 0.638298 (-2415 3800);
PAINT PINK (-2415 3800);
DISPLAY INVISIBLE (-2415 3800);
FORCEPROP 1 LAST COMMENT_BODY TRUE
J 0
(5487 -1463);
DISPLAY 0.978723 (5487 -1463);
PAINT GREEN (5487 -1463);
DISPLAY INVISIBLE (5487 -1463);
FORCEPROP 1 LAST CDS_LMAN_SYM_OUTLINE -9475,6775,100,-125
J 0
(5475 -1450);
DISPLAY 0.468085 (5475 -1450);
PAINT GREEN (5475 -1450);
DISPLAY INVISIBLE (5475 -1450);
FORCEPROP 2 LAST CDS_LIB pure_quanta
J 0
(5475 -1450);
PAINT MONO (5475 -1450);
DISPLAY INVISIBLE (5475 -1450);
FORCEADD DNS..2
(1750 2275);
PAINT RED (1750 2275);
FORCEPROP 2 LAST CDS_LIB mstr_misc
J 0
(1750 2275);
DISPLAY INVISIBLE (1750 2275);
FORCEPROP 1 LAST COMMENT_BODY TRUE
J 0
(1750 2275);
DISPLAY INVISIBLE (1750 2275);
FORCEADD DNS..2
(1725 650);
PAINT RED (1725 650);
FORCEPROP 1 LAST COMMENT_BODY TRUE
J 0
(1725 650);
DISPLAY INVISIBLE (1725 650);
FORCEPROP 2 LAST CDS_LIB mstr_misc
J 0
(1725 650);
DISPLAY INVISIBLE (1725 650);
FORCEADD DNS..2
(-2950 -825);
PAINT RED (-2950 -825);
FORCEPROP 2 LAST CDS_LIB mstr_misc
J 0
(-2950 -825);
DISPLAY INVISIBLE (-2950 -825);
FORCEPROP 1 LAST COMMENT_BODY TRUE
J 0
(-2950 -825);
DISPLAY INVISIBLE (-2950 -825);
FORCEADD DNS..2
(-2900 750);
PAINT RED (-2900 750);
FORCEPROP 1 LAST COMMENT_BODY TRUE
J 0
(-2900 750);
DISPLAY INVISIBLE (-2900 750);
FORCEPROP 2 LAST CDS_LIB mstr_misc
J 0
(-2900 750);
DISPLAY INVISIBLE (-2900 750);
FORCEADD DNS..2
(-2975 3500);
PAINT RED (-2975 3500);
FORCEPROP 1 LAST COMMENT_BODY TRUE
J 0
(-2975 3500);
DISPLAY INVISIBLE (-2975 3500);
FORCEPROP 2 LAST CDS_LIB mstr_misc
J 0
(-2975 3500);
DISPLAY INVISIBLE (-2975 3500);
FORCEADD DNS..2
(4775 1000);
PAINT RED (4775 1000);
FORCEPROP 1 LAST COMMENT_BODY TRUE
J 0
(4775 1000);
DISPLAY INVISIBLE (4775 1000);
FORCEPROP 2 LAST CDS_LIB mstr_misc
J 0
(4775 1000);
DISPLAY INVISIBLE (4775 1000);
FORCEADD DNS..2
(4800 2625);
PAINT RED (4800 2625);
FORCEPROP 2 LAST CDS_LIB mstr_misc
J 0
(4800 2625);
DISPLAY INVISIBLE (4800 2625);
FORCEPROP 1 LAST COMMENT_BODY TRUE
J 0
(4800 2625);
DISPLAY INVISIBLE (4800 2625);
FORCEADD DNS..2
(2175 4425);
PAINT RED (2175 4425);
FORCEPROP 2 LAST CDS_LIB mstr_misc
J 0
(2175 4425);
DISPLAY INVISIBLE (2175 4425);
FORCEPROP 1 LAST COMMENT_BODY TRUE
J 0
(2175 4425);
DISPLAY INVISIBLE (2175 4425);
FORCEADD DNS..2
(4200 4150);
PAINT RED (4200 4150);
FORCEPROP 2 LAST CDS_LIB mstr_misc
J 0
(4200 4150);
DISPLAY INVISIBLE (4200 4150);
FORCEPROP 1 LAST COMMENT_BODY TRUE
J 0
(4200 4150);
DISPLAY INVISIBLE (4200 4150);
FORCEADD DNS..2
(100 -475);
PAINT RED (100 -475);
FORCEPROP 2 LAST CDS_LIB mstr_misc
J 0
(100 -475);
DISPLAY INVISIBLE (100 -475);
FORCEPROP 1 LAST COMMENT_BODY TRUE
J 0
(100 -475);
DISPLAY INVISIBLE (100 -475);
FORCEADD DNS..2
(100 4000);
PAINT RED (100 4000);
FORCEPROP 2 LAST CDS_LIB mstr_misc
J 0
(100 4000);
DISPLAY INVISIBLE (100 4000);
FORCEPROP 1 LAST COMMENT_BODY TRUE
J 0
(100 4000);
DISPLAY INVISIBLE (100 4000);
FORCEADD DNS..2
(-2975 2575);
PAINT RED (-2975 2575);
FORCEPROP 2 LAST CDS_LIB mstr_misc
J 0
(-2975 2575);
DISPLAY INVISIBLE (-2975 2575);
FORCEPROP 1 LAST COMMENT_BODY TRUE
J 0
(-2975 2575);
DISPLAY INVISIBLE (-2975 2575);
FORCEADD DNS..2
(100 1275);
PAINT RED (100 1275);
FORCEPROP 1 LAST COMMENT_BODY TRUE
J 0
(100 1275);
DISPLAY INVISIBLE (100 1275);
FORCEPROP 2 LAST CDS_LIB mstr_misc
J 0
(100 1275);
DISPLAY INVISIBLE (100 1275);
FORCEADD DNS..2
(50 2625);
PAINT RED (50 2625);
FORCEPROP 1 LAST COMMENT_BODY TRUE
J 0
(50 2625);
DISPLAY INVISIBLE (50 2625);
FORCEPROP 2 LAST CDS_LIB mstr_misc
J 0
(50 2625);
DISPLAY INVISIBLE (50 2625);
WIRE 16 -1 (3875 1900)(3875 1750);
WIRE 16 -1 (-2975 -125)(-2975 -275);
WIRE 16 -1 (-2925 1450)(-2925 1350);
WIRE 16 -1 (2950 1650)(2950 1500);
WIRE 16 -1 (1725 2975)(1725 2825);
WIRE 16 -1 (2975 3275)(2975 3125);
WIRE 16 -1 (1700 1350)(1700 1200);
WIRE 16 -1 (3900 3525)(3900 3375);
WIRE 16 -1 (-800 1975)(-800 1825);
WIRE 16 -1 (-1750 1725)(-1750 1575);
WIRE 16 -1 (-1775 3075)(-1775 2925);
WIRE 16 -1 (-775 3275)(-775 3200);
WIRE 16 -1 (-3000 4200)(-3000 4100);
WIRE 16 -1 (2175 4650)(2175 4550);
WIRE 16 -1 (-1725 175)(-1725 25);
WIRE 16 -1 (-800 425)(-800 275);
WIRE 16 -1 (-675 4675)(-675 4600);
WIRE 16 -1 (-1825 4550)(-1825 4475);
WIRE 16 -1 (-2975 2800)(-2975 2700);
WIRE 16 -1 (2200 3800)(2200 3675);
WIRE 16 -1 (1750 2150)(1750 2200);
WIRE 16 -1 (1725 525)(1725 575);
WIRE 16 -1 (-2950 -950)(-2950 -900);
WIRE 16 -1 (-2900 650)(-2900 675);
WIRE 16 -1 (-2950 2000)(-2950 2025);
WIRE 16 -1 (-2975 3375)(-2975 3425);
WIRE 16 -1 (4775 925)(4775 875);
WIRE 16 -1 (3875 1000)(3875 875);
WIRE 16 -1 (2950 725)(2950 600);
WIRE 16 -1 (2975 2350)(2975 2225);
WIRE 16 -1 (3900 2625)(3900 2500);
WIRE 16 -1 (4800 2550)(4800 2500);
WIRE 16 -1 (3350 4025)(3350 3900);
WIRE 16 -1 (4200 4075)(4200 3950);
WIRE 16 -1 (-1725 -750)(-1725 -875);
WIRE 16 -1 (-800 -475)(-800 -600);
WIRE 16 -1 (100 -550)(100 -600);
WIRE 16 -1 (-1750 2175)(-1750 2050);
WIRE 16 -1 (-675 3875)(-675 3750);
WIRE 16 -1 (-1825 3575)(-1825 3450);
WIRE 16 -1 (-1750 825)(-1750 700);
WIRE 16 -1 (-800 1100)(-800 975);
WIRE 16 -1 (-775 2475)(-775 2350);
WIRE 16 -1 (100 1200)(100 1150);
WIRE 16 -1 (50 2550)(50 2500);
WIRE 16 -1 (100 3925)(100 3875);
WIRE 16 -1 (3875 1425)(3875 1400);
WIRE 16 -1 (3875 1550)(3875 1425);
WIRE 16 -1 (4775 1425)(3875 1425);
FORCEPROP 2 LAST SIG_NAME GPU_FPGA_EROT_FATALERR_ISO_N
J 0
(3965 1435);
DISPLAY 0.808511 (3965 1435);
WIRE 16 -1 (4775 1425)(4775 1125);
WIRE 16 -1 (5000 1425)(4775 1425);
WIRE 16 2175 (3600 1475)(4425 1475);
WIRE 16 2175 (4425 1475)(4425 975);
WIRE 16 2175 (3600 1475)(3600 975);
WIRE 16 2175 (3600 975)(4425 975);
WIRE 16 -1 (2950 1300)(2950 1150);
WIRE 16 -1 (3625 1150)(2950 1150);
FORCEPROP 2 LAST SIG_NAME GPU_FPGA_EROT_FATALERR
J 0
(2965 1160);
DISPLAY 0.808511 (2965 1160);
WIRE 16 -1 (2950 1125)(2950 1150);
WIRE 16 -1 (1750 2400)(1750 2500);
WIRE 16 -1 (2725 2500)(1750 2500);
FORCEPROP 2 LAST SIG_NAME GPU_PRSNT_N
J 0
(1890 2510);
DISPLAY 0.808511 (1890 2510);
WIRE 16 -1 (1725 2500)(1500 2500);
WIRE 16 -1 (1750 2500)(1725 2500);
WIRE 16 -1 (1725 2625)(1725 2500);
WIRE 16 -1 (2975 2750)(2975 2775);
WIRE 16 -1 (2975 2925)(2975 2775);
WIRE 16 -1 (3350 2775)(2975 2775);
FORCEPROP 2 LAST SIG_NAME GPU_PRSNT
J 0
(2990 2785);
DISPLAY 0.808511 (2990 2785);
WIRE 16 -1 (3650 2775)(3350 2775);
WIRE 16 -1 (3350 2775)(3350 3050);
WIRE 16 -1 (3350 3050)(3450 3050);
WIRE 16 -1 (2175 4175)(1975 4175);
WIRE 16 -1 (2175 4350)(2175 4175);
WIRE 16 -1 (2200 4175)(2200 4000);
WIRE 16 -1 (2200 4175)(2175 4175);
WIRE 16 -1 (3100 4175)(2200 4175);
FORCEPROP 2 LAST SIG_NAME GPU_WP_HW_CTRL_N
J 0
(2240 4185);
DISPLAY 0.808511 (2240 4185);
WIRE 16 -1 (1700 875)(1475 875);
WIRE 16 -1 (1700 1000)(1700 875);
WIRE 16 -1 (1725 875)(1700 875);
FORCEPROP 2 LAST SIG_NAME GPU_FPGA_EROT_FATALERR_N
J 0
(1715 885);
DISPLAY 0.808511 (1715 885);
WIRE 16 -1 (2700 875)(1725 875);
WIRE 16 -1 (1725 775)(1725 875);
WIRE 16 -1 (-2975 -600)(-3200 -600);
WIRE 16 -1 (-2975 -475)(-2975 -600);
WIRE 16 -1 (-2950 -600)(-2975 -600);
WIRE 16 -1 (-1975 -600)(-2950 -600);
FORCEPROP 2 LAST SIG_NAME GPU_FPGA_OVERT_N
J 0
(-2810 -590);
DISPLAY 0.808511 (-2810 -590);
WIRE 16 -1 (-2950 -700)(-2950 -600);
WIRE 16 -1 (-1725 -350)(-1725 -325);
WIRE 16 -1 (-1050 -325)(-1725 -325);
FORCEPROP 2 LAST SIG_NAME GPU_FPGA_OVERT
J 0
(-1710 -315);
DISPLAY 0.808511 (-1710 -315);
WIRE 16 -1 (-1725 -175)(-1725 -325);
WIRE 16 -1 (-2925 975)(-3125 975);
WIRE 16 -1 (-2925 1150)(-2925 975);
WIRE 16 -1 (-2900 975)(-2925 975);
WIRE 16 -1 (-2000 975)(-2900 975);
FORCEPROP 2 LAST SIG_NAME GPU_HMC_PRSNT_N
J 0
(-2735 985);
DISPLAY 0.808511 (-2735 985);
WIRE 16 -1 (-2900 875)(-2900 975);
WIRE 16 -1 (-2975 2325)(-3125 2325);
WIRE 16 -1 (-2975 2500)(-2975 2325);
WIRE 16 -1 (-2950 2325)(-2975 2325);
WIRE 16 -1 (-2000 2325)(-2950 2325);
FORCEPROP 2 LAST SIG_NAME GPU_BASE_HMC_READY
J 0
(-2910 2335);
DISPLAY 0.808511 (-2910 2335);
WIRE 16 -1 (-2950 2225)(-2950 2325);
WIRE 16 -1 (-3000 3725)(-3200 3725);
WIRE 16 -1 (-3000 3900)(-3000 3725);
WIRE 16 -1 (-2975 3725)(-3000 3725);
WIRE 16 -1 (-2075 3725)(-2975 3725);
FORCEPROP 2 LAST SIG_NAME GPU_FPGA_THERM_OVERT_N
J 0
(-2935 3735);
DISPLAY 0.808511 (-2935 3735);
WIRE 16 -1 (-2975 3625)(-2975 3725);
WIRE 16 -1 (3900 3050)(3900 3025);
WIRE 16 -1 (3900 3175)(3900 3050);
WIRE 16 -1 (4800 3050)(3900 3050);
FORCEPROP 2 LAST SIG_NAME GPU_PRSNT_N_ISO
J 0
(3990 3060);
DISPLAY 0.808511 (3990 3060);
WIRE 16 -1 (4800 3050)(4800 2750);
WIRE 16 -1 (5025 3050)(4800 3050);
WIRE 16 -1 (50 2900)(50 2750);
WIRE 16 -1 (200 2900)(50 2900);
WIRE 16 -1 (-775 3000)(-775 2900);
WIRE 16 -1 (50 2900)(-775 2900);
FORCEPROP 2 LAST SIG_NAME GPU_BASE_HMC_READY_ISO
J 0
(-685 2910);
DISPLAY 0.808511 (-685 2910);
WIRE 16 -1 (-775 2875)(-775 2900);
WIRE 16 -1 (-1750 2625)(-1750 2575);
WIRE 16 -1 (-1025 2625)(-1750 2625);
FORCEPROP 2 LAST SIG_NAME GPU_BASE_HMC_READY_N
J 0
(-1735 2635);
DISPLAY 0.808511 (-1735 2635);
WIRE 16 -1 (-1750 2625)(-1775 2625);
WIRE 16 -1 (-1775 2725)(-1775 2625);
WIRE 16 -1 (-925 4025)(-1825 4025);
FORCEPROP 2 LAST SIG_NAME GPU_FPGA_THERM_OVERT
J 0
(-1760 4035);
DISPLAY 0.808511 (-1760 4035);
WIRE 16 -1 (-1825 4275)(-1825 4025);
WIRE 16 -1 (-1825 3975)(-1825 4025);
WIRE 16 -1 (-1750 1250)(-1750 1225);
WIRE 16 -1 (-1750 1375)(-1750 1250);
WIRE 16 -1 (-1050 1250)(-1750 1250);
FORCEPROP 2 LAST SIG_NAME GPU_HMC_PRSNT
J 0
(-1710 1260);
DISPLAY 0.808511 (-1710 1260);
WIRE 16 -1 (-800 -50)(-800 -75);
WIRE 16 -1 (-800 75)(-800 -50);
WIRE 16 -1 (100 -50)(-800 -50);
FORCEPROP 2 LAST SIG_NAME GPU_FPGA_OVERT_ISO_N
J 0
(-710 -40);
DISPLAY 0.808511 (-710 -40);
WIRE 16 -1 (100 -50)(100 -350);
WIRE 16 -1 (325 -50)(100 -50);
WIRE 16 -1 (3350 4425)(3350 4475);
WIRE 16 -1 (4200 4475)(3350 4475);
FORCEPROP 2 LAST SIG_NAME GPU_WP_HW_CTRL_ISO
J 0
(3415 4485);
DISPLAY 0.808511 (3415 4485);
WIRE 16 -1 (4250 4475)(4200 4475);
WIRE 16 -1 (4200 4275)(4200 4475);
WIRE 16 -1 (100 1550)(100 1400);
WIRE 16 -1 (300 1550)(100 1550);
WIRE 16 -1 (-800 1625)(-800 1550);
WIRE 16 -1 (100 1550)(-800 1550);
FORCEPROP 2 LAST SIG_NAME GPU_HMC_PRSNT_ISO_N
J 0
(-660 1560);
DISPLAY 0.808511 (-660 1560);
WIRE 16 -1 (-800 1500)(-800 1550);
WIRE 16 -1 (-675 4325)(-675 4275);
WIRE 16 -1 (-675 4400)(-675 4325);
WIRE 16 -1 (100 4325)(-675 4325);
FORCEPROP 2 LAST SIG_NAME GPU_FPGA_THERM_OVERT_ISO_N
J 0
(-610 4335);
DISPLAY 0.808511 (-610 4335);
WIRE 16 -1 (100 4125)(100 4325);
WIRE 16 -1 (400 4325)(100 4325);
DOT 1 (2200 4175);
DOT 1 (1750 2500);
DOT 1 (1725 875);
DOT 1 (-2950 -600);
DOT 1 (-2900 975);
DOT 1 (-2950 2325);
DOT 1 (-2975 3725);
DOT 1 (3350 2775);
DOT 1 (-1825 4025);
DOT 1 (-3000 3725);
DOT 1 (-1750 2625);
DOT 1 (50 2900);
DOT 1 (100 1550);
DOT 1 (-800 1550);
DOT 1 (-1750 1250);
DOT 1 (-2975 2325);
DOT 1 (-2925 975);
DOT 1 (-675 4325);
DOT 1 (100 4325);
DOT 1 (-775 2900);
DOT 1 (-2975 -600);
DOT 1 (-1725 -325);
DOT 1 (-800 -50);
DOT 1 (100 -50);
DOT 1 (4200 4475);
DOT 1 (2175 4175);
DOT 1 (4775 1425);
DOT 1 (3875 1425);
DOT 1 (2950 1150);
DOT 1 (1700 875);
DOT 1 (1725 2500);
DOT 1 (2975 2775);
DOT 1 (3900 3050);
DOT 1 (4800 3050);
FORCENOTE
20220802 CHANGE TO Q107
(3525 2325) 0;
DISPLAY LEFT (3525 2325);
DISPLAY 1.063830 (3525 2325);
PAINT WHITE (3525 2325);
FORCENOTE
20220802 CHANGE TO Q108
(3550 750) 0;
DISPLAY LEFT (3550 750);
DISPLAY 1.063830 (3550 750);
PAINT WHITE (3550 750);
QUIT
